(kicad_sch
	(version 20231120)
	(generator "eeschema")
	(generator_version "8.0")
	(paper "A3")
	(title_block
		(title "Jetson Orin Baseboard")
		(date "2025-03-12")
		(rev "1.3.4")
		(company "Antmicro Ltd")
		(comment 1 "www.antmicro.com")
	)
	(junction
		(at 162.56 50.8)
		(diameter 0)
		(color 0 0 0 0)
	)
	(junction
		(at 398.78 182.88)
		(diameter 0)
		(color 0 0 0 0)
	)
	(junction
		(at 334.01 111.76)
		(diameter 0)
		(color 0 0 0 0)
	)
	(junction
		(at 334.01 129.54)
		(diameter 0)
		(color 0 0 0 0)
	)
	(junction
		(at 317.5 111.76)
		(diameter 0)
		(color 0 0 0 0)
	)
	(junction
		(at 92.71 260.35)
		(diameter 0)
		(color 0 0 0 0)
	)
	(junction
		(at 312.42 179.07)
		(diameter 0)
		(color 0 0 0 0)
	)
	(junction
		(at 279.4 179.07)
		(diameter 0)
		(color 0 0 0 0)
	)
	(junction
		(at 185.42 88.9)
		(diameter 0)
		(color 0 0 0 0)
	)
	(junction
		(at 57.15 54.61)
		(diameter 0)
		(color 0 0 0 0)
	)
	(junction
		(at 29.21 149.86)
		(diameter 0)
		(color 0 0 0 0)
	)
	(junction
		(at 398.78 218.44)
		(diameter 0)
		(color 0 0 0 0)
	)
	(junction
		(at 317.5 58.42)
		(diameter 0)
		(color 0 0 0 0)
	)
	(junction
		(at 334.01 60.96)
		(diameter 0)
		(color 0 0 0 0)
	)
	(junction
		(at 317.5 96.52)
		(diameter 0)
		(color 0 0 0 0)
	)
	(junction
		(at 398.78 187.96)
		(diameter 0)
		(color 0 0 0 0)
	)
	(junction
		(at 317.5 43.18)
		(diameter 0)
		(color 0 0 0 0)
	)
	(junction
		(at 265.43 232.41)
		(diameter 0)
		(color 0 0 0 0)
	)
	(junction
		(at 317.5 124.46)
		(diameter 0)
		(color 0 0 0 0)
	)
	(junction
		(at 152.4 34.29)
		(diameter 0)
		(color 0 0 0 0)
	)
	(junction
		(at 314.96 121.92)
		(diameter 0)
		(color 0 0 0 0)
	)
	(junction
		(at 67.31 60.96)
		(diameter 0)
		(color 0 0 0 0)
	)
	(junction
		(at 334.01 124.46)
		(diameter 0)
		(color 0 0 0 0)
	)
	(junction
		(at 317.5 66.04)
		(diameter 0)
		(color 0 0 0 0)
	)
	(junction
		(at 334.01 53.34)
		(diameter 0)
		(color 0 0 0 0)
	)
	(junction
		(at 398.78 167.64)
		(diameter 0)
		(color 0 0 0 0)
	)
	(junction
		(at 265.43 274.32)
		(diameter 0)
		(color 0 0 0 0)
	)
	(junction
		(at 398.78 203.2)
		(diameter 0)
		(color 0 0 0 0)
	)
	(junction
		(at 398.78 177.8)
		(diameter 0)
		(color 0 0 0 0)
	)
	(junction
		(at 314.96 132.08)
		(diameter 0)
		(color 0 0 0 0)
	)
	(junction
		(at 317.5 81.28)
		(diameter 0)
		(color 0 0 0 0)
	)
	(junction
		(at 398.78 228.6)
		(diameter 0)
		(color 0 0 0 0)
	)
	(junction
		(at 44.45 67.31)
		(diameter 0)
		(color 0 0 0 0)
	)
	(junction
		(at 261.62 232.41)
		(diameter 0)
		(color 0 0 0 0)
	)
	(junction
		(at 267.97 245.11)
		(diameter 0)
		(color 0 0 0 0)
	)
	(junction
		(at 398.78 223.52)
		(diameter 0)
		(color 0 0 0 0)
	)
	(junction
		(at 398.78 208.28)
		(diameter 0)
		(color 0 0 0 0)
	)
	(junction
		(at 191.77 86.36)
		(diameter 0)
		(color 0 0 0 0)
	)
	(junction
		(at 398.78 162.56)
		(diameter 0)
		(color 0 0 0 0)
	)
	(junction
		(at 334.01 68.58)
		(diameter 0)
		(color 0 0 0 0)
	)
	(junction
		(at 295.91 179.07)
		(diameter 0)
		(color 0 0 0 0)
	)
	(junction
		(at 34.29 163.83)
		(diameter 0)
		(color 0 0 0 0)
	)
	(junction
		(at 334.01 45.72)
		(diameter 0)
		(color 0 0 0 0)
	)
	(junction
		(at 36.83 232.41)
		(diameter 0)
		(color 0 0 0 0)
	)
	(junction
		(at 267.97 261.62)
		(diameter 0)
		(color 0 0 0 0)
	)
	(junction
		(at 204.47 45.72)
		(diameter 0)
		(color 0 0 0 0)
	)
	(junction
		(at 398.78 172.72)
		(diameter 0)
		(color 0 0 0 0)
	)
	(junction
		(at 336.55 132.08)
		(diameter 0)
		(color 0 0 0 0)
	)
	(junction
		(at 317.5 50.8)
		(diameter 0)
		(color 0 0 0 0)
	)
	(junction
		(at 189.23 53.34)
		(diameter 0)
		(color 0 0 0 0)
	)
	(junction
		(at 265.43 245.11)
		(diameter 0)
		(color 0 0 0 0)
	)
	(junction
		(at 398.78 233.68)
		(diameter 0)
		(color 0 0 0 0)
	)
	(junction
		(at 334.01 38.1)
		(diameter 0)
		(color 0 0 0 0)
	)
	(junction
		(at 246.38 179.07)
		(diameter 0)
		(color 0 0 0 0)
	)
	(junction
		(at 317.5 129.54)
		(diameter 0)
		(color 0 0 0 0)
	)
	(junction
		(at 199.39 254)
		(diameter 0)
		(color 0 0 0 0)
	)
	(junction
		(at 267.97 232.41)
		(diameter 0)
		(color 0 0 0 0)
	)
	(junction
		(at 217.17 91.44)
		(diameter 0)
		(color 0 0 0 0)
	)
	(junction
		(at 267.97 274.32)
		(diameter 0)
		(color 0 0 0 0)
	)
	(junction
		(at 334.01 96.52)
		(diameter 0)
		(color 0 0 0 0)
	)
	(junction
		(at 162.56 34.29)
		(diameter 0)
		(color 0 0 0 0)
	)
	(junction
		(at 140.97 254)
		(diameter 0)
		(color 0 0 0 0)
	)
	(junction
		(at 398.78 193.04)
		(diameter 0)
		(color 0 0 0 0)
	)
	(junction
		(at 44.45 242.57)
		(diameter 0)
		(color 0 0 0 0)
	)
	(junction
		(at 265.43 261.62)
		(diameter 0)
		(color 0 0 0 0)
	)
	(junction
		(at 398.78 198.12)
		(diameter 0)
		(color 0 0 0 0)
	)
	(junction
		(at 62.23 149.86)
		(diameter 0)
		(color 0 0 0 0)
	)
	(junction
		(at 398.78 238.76)
		(diameter 0)
		(color 0 0 0 0)
	)
	(junction
		(at 398.78 243.84)
		(diameter 0)
		(color 0 0 0 0)
	)
	(junction
		(at 334.01 81.28)
		(diameter 0)
		(color 0 0 0 0)
	)
	(junction
		(at 262.89 179.07)
		(diameter 0)
		(color 0 0 0 0)
	)
	(junction
		(at 398.78 213.36)
		(diameter 0)
		(color 0 0 0 0)
	)
	(junction
		(at 261.62 261.62)
		(diameter 0)
		(color 0 0 0 0)
	)
	(no_connect
		(at 121.92 199.39)
	)
	(no_connect
		(at 189.23 199.39)
	)
	(no_connect
		(at 189.23 196.85)
	)
	(no_connect
		(at 199.39 196.85)
	)
	(no_connect
		(at 199.39 199.39)
	)
	(no_connect
		(at 132.08 199.39)
	)
	(no_connect
		(at 132.08 161.29)
	)
	(no_connect
		(at 132.08 163.83)
	)
	(no_connect
		(at 121.92 163.83)
	)
	(no_connect
		(at 121.92 161.29)
	)
	(no_connect
		(at 172.72 48.26)
	)
	(no_connect
		(at 74.93 232.41)
	)
	(no_connect
		(at 78.74 265.43)
	)
	(no_connect
		(at 88.9 265.43)
	)
	(no_connect
		(at 88.9 81.28)
	)
	(no_connect
		(at 76.2 161.29)
	)
	(no_connect
		(at 74.93 240.03)
	)
	(no_connect
		(at 76.2 163.83)
	)
	(wire
		(pts
			(xy 328.93 237.49) (xy 331.47 237.49)
		)
		(stroke
			(width 0)
			(type default)
		)
	)
	(wire
		(pts
			(xy 62.23 149.86) (xy 62.23 151.13)
		)
		(stroke
			(width 0)
			(type default)
		)
	)
	(wire
		(pts
			(xy 267.97 245.11) (xy 267.97 243.84)
		)
		(stroke
			(width 0)
			(type default)
		)
	)
	(wire
		(pts
			(xy 177.8 176.53) (xy 189.23 176.53)
		)
		(stroke
			(width 0)
			(type default)
		)
	)
	(wire
		(pts
			(xy 109.22 156.21) (xy 121.92 156.21)
		)
		(stroke
			(width 0)
			(type default)
		)
	)
	(wire
		(pts
			(xy 331.47 99.06) (xy 359.41 99.06)
		)
		(stroke
			(width 0)
			(type default)
		)
	)
	(wire
		(pts
			(xy 175.26 191.77) (xy 189.23 191.77)
		)
		(stroke
			(width 0)
			(type default)
		)
	)
	(wire
		(pts
			(xy 149.86 232.41) (xy 149.86 233.68)
		)
		(stroke
			(width 0)
			(type default)
		)
	)
	(wire
		(pts
			(xy 271.78 45.72) (xy 276.86 45.72)
		)
		(stroke
			(width 0)
			(type default)
		)
	)
	(wire
		(pts
			(xy 189.23 50.8) (xy 189.23 53.34)
		)
		(stroke
			(width 0)
			(type default)
		)
	)
	(wire
		(pts
			(xy 62.23 157.48) (xy 62.23 156.21)
		)
		(stroke
			(width 0)
			(type default)
		)
	)
	(wire
		(pts
			(xy 115.57 60.96) (xy 113.03 60.96)
		)
		(stroke
			(width 0)
			(type default)
		)
	)
	(wire
		(pts
			(xy 149.86 245.11) (xy 149.86 246.38)
		)
		(stroke
			(width 0)
			(type default)
		)
	)
	(wire
		(pts
			(xy 57.15 53.34) (xy 57.15 54.61)
		)
		(stroke
			(width 0)
			(type default)
		)
	)
	(wire
		(pts
			(xy 295.91 167.64) (xy 295.91 168.91)
		)
		(stroke
			(width 0)
			(type default)
		)
	)
	(wire
		(pts
			(xy 140.97 251.46) (xy 140.97 254)
		)
		(stroke
			(width 0)
			(type default)
		)
	)
	(wire
		(pts
			(xy 111.76 179.07) (xy 121.92 179.07)
		)
		(stroke
			(width 0)
			(type default)
		)
	)
	(wire
		(pts
			(xy 154.94 196.85) (xy 132.08 196.85)
		)
		(stroke
			(width 0)
			(type default)
		)
	)
	(wire
		(pts
			(xy 68.58 257.81) (xy 78.74 257.81)
		)
		(stroke
			(width 0)
			(type default)
		)
	)
	(wire
		(pts
			(xy 34.29 232.41) (xy 36.83 232.41)
		)
		(stroke
			(width 0)
			(type default)
		)
	)
	(wire
		(pts
			(xy 173.99 88.9) (xy 185.42 88.9)
		)
		(stroke
			(width 0)
			(type default)
		)
	)
	(wire
		(pts
			(xy 204.47 54.61) (xy 204.47 55.88)
		)
		(stroke
			(width 0)
			(type default)
		)
	)
	(wire
		(pts
			(xy 152.4 40.64) (xy 152.4 41.91)
		)
		(stroke
			(width 0)
			(type default)
		)
	)
	(wire
		(pts
			(xy 82.55 234.95) (xy 87.63 234.95)
		)
		(stroke
			(width 0)
			(type default)
		)
	)
	(wire
		(pts
			(xy 330.2 246.38) (xy 330.2 245.11)
		)
		(stroke
			(width 0)
			(type default)
		)
	)
	(wire
		(pts
			(xy 320.04 66.04) (xy 317.5 66.04)
		)
		(stroke
			(width 0)
			(type default)
		)
	)
	(wire
		(pts
			(xy 292.1 109.22) (xy 320.04 109.22)
		)
		(stroke
			(width 0)
			(type default)
		)
	)
	(wire
		(pts
			(xy 88.9 83.82) (xy 90.17 83.82)
		)
		(stroke
			(width 0)
			(type default)
		)
	)
	(wire
		(pts
			(xy 115.57 76.2) (xy 113.03 76.2)
		)
		(stroke
			(width 0)
			(type default)
		)
	)
	(wire
		(pts
			(xy 152.4 33.02) (xy 152.4 34.29)
		)
		(stroke
			(width 0)
			(type default)
		)
	)
	(wire
		(pts
			(xy 317.5 58.42) (xy 317.5 50.8)
		)
		(stroke
			(width 0)
			(type default)
		)
	)
	(wire
		(pts
			(xy 62.23 148.59) (xy 62.23 149.86)
		)
		(stroke
			(width 0)
			(type default)
		)
	)
	(wire
		(pts
			(xy 110.49 191.77) (xy 121.92 191.77)
		)
		(stroke
			(width 0)
			(type default)
		)
	)
	(wire
		(pts
			(xy 317.5 66.04) (xy 317.5 81.28)
		)
		(stroke
			(width 0)
			(type default)
		)
	)
	(wire
		(pts
			(xy 314.96 119.38) (xy 314.96 121.92)
		)
		(stroke
			(width 0)
			(type default)
		)
	)
	(wire
		(pts
			(xy 111.76 181.61) (xy 121.92 181.61)
		)
		(stroke
			(width 0)
			(type default)
		)
	)
	(wire
		(pts
			(xy 271.78 40.64) (xy 280.67 40.64)
		)
		(stroke
			(width 0)
			(type default)
		)
	)
	(wire
		(pts
			(xy 344.17 119.38) (xy 331.47 119.38)
		)
		(stroke
			(width 0)
			(type default)
		)
	)
	(wire
		(pts
			(xy 330.2 245.11) (xy 331.47 245.11)
		)
		(stroke
			(width 0)
			(type default)
		)
	)
	(wire
		(pts
			(xy 393.7 218.44) (xy 398.78 218.44)
		)
		(stroke
			(width 0)
			(type default)
		)
	)
	(wire
		(pts
			(xy 38.1 71.12) (xy 41.91 71.12)
		)
		(stroke
			(width 0)
			(type default)
		)
	)
	(wire
		(pts
			(xy 265.43 232.41) (xy 265.43 233.68)
		)
		(stroke
			(width 0)
			(type default)
		)
	)
	(wire
		(pts
			(xy 398.78 172.72) (xy 398.78 177.8)
		)
		(stroke
			(width 0)
			(type default)
		)
	)
	(wire
		(pts
			(xy 336.55 132.08) (xy 336.55 134.62)
		)
		(stroke
			(width 0)
			(type default)
		)
	)
	(wire
		(pts
			(xy 314.96 166.37) (xy 312.42 166.37)
		)
		(stroke
			(width 0)
			(type default)
		)
	)
	(wire
		(pts
			(xy 57.15 163.83) (xy 57.15 149.86)
		)
		(stroke
			(width 0)
			(type default)
		)
	)
	(wire
		(pts
			(xy 154.94 158.75) (xy 132.08 158.75)
		)
		(stroke
			(width 0)
			(type default)
		)
	)
	(wire
		(pts
			(xy 199.39 251.46) (xy 199.39 254)
		)
		(stroke
			(width 0)
			(type default)
		)
	)
	(wire
		(pts
			(xy 331.47 60.96) (xy 334.01 60.96)
		)
		(stroke
			(width 0)
			(type default)
		)
	)
	(wire
		(pts
			(xy 331.47 111.76) (xy 334.01 111.76)
		)
		(stroke
			(width 0)
			(type default)
		)
	)
	(wire
		(pts
			(xy 271.78 38.1) (xy 276.86 38.1)
		)
		(stroke
			(width 0)
			(type default)
		)
	)
	(wire
		(pts
			(xy 152.4 34.29) (xy 152.4 35.56)
		)
		(stroke
			(width 0)
			(type default)
		)
	)
	(wire
		(pts
			(xy 154.94 179.07) (xy 132.08 179.07)
		)
		(stroke
			(width 0)
			(type default)
		)
	)
	(wire
		(pts
			(xy 334.01 53.34) (xy 331.47 53.34)
		)
		(stroke
			(width 0)
			(type default)
		)
	)
	(wire
		(pts
			(xy 55.88 166.37) (xy 76.2 166.37)
		)
		(stroke
			(width 0)
			(type default)
		)
	)
	(wire
		(pts
			(xy 55.88 81.28) (xy 68.58 81.28)
		)
		(stroke
			(width 0)
			(type default)
		)
	)
	(wire
		(pts
			(xy 36.83 229.87) (xy 36.83 232.41)
		)
		(stroke
			(width 0)
			(type default)
		)
	)
	(wire
		(pts
			(xy 73.66 173.99) (xy 73.66 175.26)
		)
		(stroke
			(width 0)
			(type default)
		)
	)
	(wire
		(pts
			(xy 398.78 243.84) (xy 398.78 246.38)
		)
		(stroke
			(width 0)
			(type default)
		)
	)
	(wire
		(pts
			(xy 44.45 242.57) (xy 44.45 247.65)
		)
		(stroke
			(width 0)
			(type default)
		)
	)
	(wire
		(pts
			(xy 115.57 73.66) (xy 113.03 73.66)
		)
		(stroke
			(width 0)
			(type default)
		)
	)
	(wire
		(pts
			(xy 191.77 86.36) (xy 218.44 86.36)
		)
		(stroke
			(width 0)
			(type default)
		)
	)
	(wire
		(pts
			(xy 44.45 53.34) (xy 44.45 55.88)
		)
		(stroke
			(width 0)
			(type default)
		)
	)
	(wire
		(pts
			(xy 194.31 48.26) (xy 194.31 49.53)
		)
		(stroke
			(width 0)
			(type default)
		)
	)
	(wire
		(pts
			(xy 39.37 240.03) (xy 45.72 240.03)
		)
		(stroke
			(width 0)
			(type default)
		)
	)
	(wire
		(pts
			(xy 46.99 73.66) (xy 68.58 73.66)
		)
		(stroke
			(width 0)
			(type default)
		)
	)
	(wire
		(pts
			(xy 154.94 191.77) (xy 132.08 191.77)
		)
		(stroke
			(width 0)
			(type default)
		)
	)
	(wire
		(pts
			(xy 265.43 243.84) (xy 265.43 245.11)
		)
		(stroke
			(width 0)
			(type default)
		)
	)
	(wire
		(pts
			(xy 224.79 163.83) (xy 199.39 163.83)
		)
		(stroke
			(width 0)
			(type default)
		)
	)
	(wire
		(pts
			(xy 181.61 139.7) (xy 189.23 139.7)
		)
		(stroke
			(width 0)
			(type default)
		)
	)
	(wire
		(pts
			(xy 353.06 238.76) (xy 388.62 238.76)
		)
		(stroke
			(width 0)
			(type default)
		)
	)
	(wire
		(pts
			(xy 187.96 50.8) (xy 189.23 50.8)
		)
		(stroke
			(width 0)
			(type default)
		)
	)
	(wire
		(pts
			(xy 354.33 208.28) (xy 388.62 208.28)
		)
		(stroke
			(width 0)
			(type default)
		)
	)
	(wire
		(pts
			(xy 82.55 240.03) (xy 87.63 240.03)
		)
		(stroke
			(width 0)
			(type default)
		)
	)
	(wire
		(pts
			(xy 88.9 76.2) (xy 102.87 76.2)
		)
		(stroke
			(width 0)
			(type default)
		)
	)
	(polyline
		(pts
			(xy 231.14 205.74) (xy 231.14 118.11)
		)
		(stroke
			(width 0)
			(type default)
		)
	)
	(wire
		(pts
			(xy 317.5 124.46) (xy 317.5 129.54)
		)
		(stroke
			(width 0)
			(type default)
		)
	)
	(wire
		(pts
			(xy 331.47 48.26) (xy 342.9 48.26)
		)
		(stroke
			(width 0)
			(type default)
		)
	)
	(wire
		(pts
			(xy 246.38 167.64) (xy 246.38 168.91)
		)
		(stroke
			(width 0)
			(type default)
		)
	)
	(wire
		(pts
			(xy 191.77 86.36) (xy 191.77 91.44)
		)
		(stroke
			(width 0)
			(type default)
		)
	)
	(wire
		(pts
			(xy 331.47 116.84) (xy 344.17 116.84)
		)
		(stroke
			(width 0)
			(type default)
		)
	)
	(wire
		(pts
			(xy 189.23 53.34) (xy 189.23 55.88)
		)
		(stroke
			(width 0)
			(type default)
		)
	)
	(wire
		(pts
			(xy 372.11 198.12) (xy 388.62 198.12)
		)
		(stroke
			(width 0)
			(type default)
		)
	)
	(wire
		(pts
			(xy 285.75 40.64) (xy 320.04 40.64)
		)
		(stroke
			(width 0)
			(type default)
		)
	)
	(wire
		(pts
			(xy 55.88 82.55) (xy 55.88 81.28)
		)
		(stroke
			(width 0)
			(type default)
		)
	)
	(wire
		(pts
			(xy 208.28 256.54) (xy 208.28 261.62)
		)
		(stroke
			(width 0)
			(type default)
		)
	)
	(wire
		(pts
			(xy 74.93 237.49) (xy 81.28 237.49)
		)
		(stroke
			(width 0)
			(type default)
		)
	)
	(wire
		(pts
			(xy 162.56 57.15) (xy 162.56 58.42)
		)
		(stroke
			(width 0)
			(type default)
		)
	)
	(wire
		(pts
			(xy 267.97 261.62) (xy 267.97 262.89)
		)
		(stroke
			(width 0)
			(type default)
		)
	)
	(wire
		(pts
			(xy 224.79 139.7) (xy 199.39 139.7)
		)
		(stroke
			(width 0)
			(type default)
		)
	)
	(wire
		(pts
			(xy 281.94 38.1) (xy 320.04 38.1)
		)
		(stroke
			(width 0)
			(type default)
		)
	)
	(wire
		(pts
			(xy 173.99 163.83) (xy 189.23 163.83)
		)
		(stroke
			(width 0)
			(type default)
		)
	)
	(wire
		(pts
			(xy 398.78 162.56) (xy 398.78 167.64)
		)
		(stroke
			(width 0)
			(type default)
		)
	)
	(wire
		(pts
			(xy 265.43 261.62) (xy 267.97 261.62)
		)
		(stroke
			(width 0)
			(type default)
		)
	)
	(wire
		(pts
			(xy 271.78 88.9) (xy 279.4 88.9)
		)
		(stroke
			(width 0)
			(type default)
		)
	)
	(wire
		(pts
			(xy 154.94 176.53) (xy 132.08 176.53)
		)
		(stroke
			(width 0)
			(type default)
		)
	)
	(wire
		(pts
			(xy 353.06 243.84) (xy 388.62 243.84)
		)
		(stroke
			(width 0)
			(type default)
		)
	)
	(wire
		(pts
			(xy 261.62 232.41) (xy 261.62 236.22)
		)
		(stroke
			(width 0)
			(type default)
		)
	)
	(wire
		(pts
			(xy 67.31 60.96) (xy 67.31 54.61)
		)
		(stroke
			(width 0)
			(type default)
		)
	)
	(wire
		(pts
			(xy 44.45 60.96) (xy 44.45 67.31)
		)
		(stroke
			(width 0)
			(type default)
		)
	)
	(wire
		(pts
			(xy 354.33 182.88) (xy 388.62 182.88)
		)
		(stroke
			(width 0)
			(type default)
		)
	)
	(wire
		(pts
			(xy 162.56 50.8) (xy 162.56 52.07)
		)
		(stroke
			(width 0)
			(type default)
		)
	)
	(wire
		(pts
			(xy 57.15 60.96) (xy 57.15 62.23)
		)
		(stroke
			(width 0)
			(type default)
		)
	)
	(wire
		(pts
			(xy 334.01 35.56) (xy 334.01 38.1)
		)
		(stroke
			(width 0)
			(type default)
		)
	)
	(wire
		(pts
			(xy 38.1 73.66) (xy 41.91 73.66)
		)
		(stroke
			(width 0)
			(type default)
		)
	)
	(wire
		(pts
			(xy 295.91 179.07) (xy 307.34 179.07)
		)
		(stroke
			(width 0)
			(type default)
		)
	)
	(wire
		(pts
			(xy 52.07 77.47) (xy 68.58 77.47)
		)
		(stroke
			(width 0)
			(type default)
		)
	)
	(wire
		(pts
			(xy 314.96 121.92) (xy 320.04 121.92)
		)
		(stroke
			(width 0)
			(type default)
		)
	)
	(wire
		(pts
			(xy 57.15 55.88) (xy 57.15 54.61)
		)
		(stroke
			(width 0)
			(type default)
		)
	)
	(wire
		(pts
			(xy 115.57 63.5) (xy 113.03 63.5)
		)
		(stroke
			(width 0)
			(type default)
		)
	)
	(wire
		(pts
			(xy 398.78 198.12) (xy 398.78 203.2)
		)
		(stroke
			(width 0)
			(type default)
		)
	)
	(wire
		(pts
			(xy 317.5 81.28) (xy 320.04 81.28)
		)
		(stroke
			(width 0)
			(type default)
		)
	)
	(wire
		(pts
			(xy 372.11 193.04) (xy 388.62 193.04)
		)
		(stroke
			(width 0)
			(type default)
		)
	)
	(polyline
		(pts
			(xy 231.14 12.7) (xy 231.14 118.11)
		)
		(stroke
			(width 0)
			(type default)
		)
	)
	(wire
		(pts
			(xy 199.39 254) (xy 201.93 254)
		)
		(stroke
			(width 0)
			(type default)
		)
	)
	(wire
		(pts
			(xy 44.45 242.57) (xy 45.72 242.57)
		)
		(stroke
			(width 0)
			(type default)
		)
	)
	(wire
		(pts
			(xy 372.11 228.6) (xy 388.62 228.6)
		)
		(stroke
			(width 0)
			(type default)
		)
	)
	(wire
		(pts
			(xy 372.11 167.64) (xy 388.62 167.64)
		)
		(stroke
			(width 0)
			(type default)
		)
	)
	(wire
		(pts
			(xy 393.7 172.72) (xy 398.78 172.72)
		)
		(stroke
			(width 0)
			(type default)
		)
	)
	(wire
		(pts
			(xy 194.31 55.88) (xy 194.31 54.61)
		)
		(stroke
			(width 0)
			(type default)
		)
	)
	(wire
		(pts
			(xy 393.7 233.68) (xy 398.78 233.68)
		)
		(stroke
			(width 0)
			(type default)
		)
	)
	(wire
		(pts
			(xy 140.97 260.35) (xy 140.97 261.62)
		)
		(stroke
			(width 0)
			(type default)
		)
	)
	(wire
		(pts
			(xy 97.79 232.41) (xy 99.06 232.41)
		)
		(stroke
			(width 0)
			(type default)
		)
	)
	(wire
		(pts
			(xy 173.99 156.21) (xy 189.23 156.21)
		)
		(stroke
			(width 0)
			(type default)
		)
	)
	(wire
		(pts
			(xy 398.78 203.2) (xy 398.78 208.28)
		)
		(stroke
			(width 0)
			(type default)
		)
	)
	(wire
		(pts
			(xy 44.45 237.49) (xy 45.72 237.49)
		)
		(stroke
			(width 0)
			(type default)
		)
	)
	(wire
		(pts
			(xy 261.62 260.35) (xy 261.62 261.62)
		)
		(stroke
			(width 0)
			(type default)
		)
	)
	(wire
		(pts
			(xy 334.01 60.96) (xy 334.01 68.58)
		)
		(stroke
			(width 0)
			(type default)
		)
	)
	(wire
		(pts
			(xy 279.4 173.99) (xy 279.4 179.07)
		)
		(stroke
			(width 0)
			(type default)
		)
	)
	(wire
		(pts
			(xy 331.47 83.82) (xy 359.41 83.82)
		)
		(stroke
			(width 0)
			(type default)
		)
	)
	(wire
		(pts
			(xy 279.4 167.64) (xy 279.4 168.91)
		)
		(stroke
			(width 0)
			(type default)
		)
	)
	(wire
		(pts
			(xy 334.01 60.96) (xy 334.01 53.34)
		)
		(stroke
			(width 0)
			(type default)
		)
	)
	(wire
		(pts
			(xy 154.94 181.61) (xy 132.08 181.61)
		)
		(stroke
			(width 0)
			(type default)
		)
	)
	(wire
		(pts
			(xy 331.47 35.56) (xy 334.01 35.56)
		)
		(stroke
			(width 0)
			(type default)
		)
	)
	(wire
		(pts
			(xy 334.01 38.1) (xy 334.01 45.72)
		)
		(stroke
			(width 0)
			(type default)
		)
	)
	(wire
		(pts
			(xy 271.78 60.96) (xy 276.86 60.96)
		)
		(stroke
			(width 0)
			(type default)
		)
	)
	(wire
		(pts
			(xy 398.78 238.76) (xy 398.78 243.84)
		)
		(stroke
			(width 0)
			(type default)
		)
	)
	(wire
		(pts
			(xy 88.9 66.04) (xy 102.87 66.04)
		)
		(stroke
			(width 0)
			(type default)
		)
	)
	(wire
		(pts
			(xy 281.94 60.96) (xy 320.04 60.96)
		)
		(stroke
			(width 0)
			(type default)
		)
	)
	(wire
		(pts
			(xy 292.1 101.6) (xy 320.04 101.6)
		)
		(stroke
			(width 0)
			(type default)
		)
	)
	(wire
		(pts
			(xy 224.79 156.21) (xy 199.39 156.21)
		)
		(stroke
			(width 0)
			(type default)
		)
	)
	(wire
		(pts
			(xy 328.93 242.57) (xy 331.47 242.57)
		)
		(stroke
			(width 0)
			(type default)
		)
	)
	(wire
		(pts
			(xy 88.9 71.12) (xy 102.87 71.12)
		)
		(stroke
			(width 0)
			(type default)
		)
	)
	(wire
		(pts
			(xy 314.96 134.62) (xy 314.96 132.08)
		)
		(stroke
			(width 0)
			(type default)
		)
	)
	(wire
		(pts
			(xy 349.25 116.84) (xy 359.41 116.84)
		)
		(stroke
			(width 0)
			(type default)
		)
	)
	(wire
		(pts
			(xy 279.4 179.07) (xy 290.83 179.07)
		)
		(stroke
			(width 0)
			(type default)
		)
	)
	(wire
		(pts
			(xy 109.22 158.75) (xy 121.92 158.75)
		)
		(stroke
			(width 0)
			(type default)
		)
	)
	(wire
		(pts
			(xy 267.97 245.11) (xy 267.97 246.38)
		)
		(stroke
			(width 0)
			(type default)
		)
	)
	(wire
		(pts
			(xy 177.8 181.61) (xy 189.23 181.61)
		)
		(stroke
			(width 0)
			(type default)
		)
	)
	(wire
		(pts
			(xy 154.94 143.51) (xy 132.08 143.51)
		)
		(stroke
			(width 0)
			(type default)
		)
	)
	(wire
		(pts
			(xy 372.11 223.52) (xy 388.62 223.52)
		)
		(stroke
			(width 0)
			(type default)
		)
	)
	(wire
		(pts
			(xy 53.34 262.89) (xy 78.74 262.89)
		)
		(stroke
			(width 0)
			(type default)
		)
	)
	(wire
		(pts
			(xy 292.1 83.82) (xy 320.04 83.82)
		)
		(stroke
			(width 0)
			(type default)
		)
	)
	(wire
		(pts
			(xy 267.97 261.62) (xy 270.51 261.62)
		)
		(stroke
			(width 0)
			(type default)
		)
	)
	(wire
		(pts
			(xy 111.76 176.53) (xy 121.92 176.53)
		)
		(stroke
			(width 0)
			(type default)
		)
	)
	(wire
		(pts
			(xy 109.22 138.43) (xy 121.92 138.43)
		)
		(stroke
			(width 0)
			(type default)
		)
	)
	(wire
		(pts
			(xy 317.5 58.42) (xy 317.5 66.04)
		)
		(stroke
			(width 0)
			(type default)
		)
	)
	(wire
		(pts
			(xy 97.79 237.49) (xy 99.06 237.49)
		)
		(stroke
			(width 0)
			(type default)
		)
	)
	(wire
		(pts
			(xy 354.33 213.36) (xy 388.62 213.36)
		)
		(stroke
			(width 0)
			(type default)
		)
	)
	(wire
		(pts
			(xy 308.61 114.3) (xy 320.04 114.3)
		)
		(stroke
			(width 0)
			(type default)
		)
	)
	(polyline
		(pts
			(xy 299.72 205.74) (xy 299.72 252.73)
		)
		(stroke
			(width 0)
			(type default)
		)
	)
	(wire
		(pts
			(xy 372.11 172.72) (xy 388.62 172.72)
		)
		(stroke
			(width 0)
			(type default)
		)
	)
	(wire
		(pts
			(xy 35.56 171.45) (xy 34.29 171.45)
		)
		(stroke
			(width 0)
			(type default)
		)
	)
	(wire
		(pts
			(xy 261.62 274.32) (xy 265.43 274.32)
		)
		(stroke
			(width 0)
			(type default)
		)
	)
	(wire
		(pts
			(xy 57.15 175.26) (xy 57.15 171.45)
		)
		(stroke
			(width 0)
			(type default)
		)
	)
	(wire
		(pts
			(xy 171.45 34.29) (xy 162.56 34.29)
		)
		(stroke
			(width 0)
			(type default)
		)
	)
	(wire
		(pts
			(xy 177.8 179.07) (xy 189.23 179.07)
		)
		(stroke
			(width 0)
			(type default)
		)
	)
	(wire
		(pts
			(xy 53.34 260.35) (xy 78.74 260.35)
		)
		(stroke
			(width 0)
			(type default)
		)
	)
	(wire
		(pts
			(xy 224.79 194.31) (xy 199.39 194.31)
		)
		(stroke
			(width 0)
			(type default)
		)
	)
	(wire
		(pts
			(xy 317.5 43.18) (xy 320.04 43.18)
		)
		(stroke
			(width 0)
			(type default)
		)
	)
	(wire
		(pts
			(xy 204.47 45.72) (xy 214.63 45.72)
		)
		(stroke
			(width 0)
			(type default)
		)
	)
	(wire
		(pts
			(xy 115.57 66.04) (xy 113.03 66.04)
		)
		(stroke
			(width 0)
			(type default)
		)
	)
	(wire
		(pts
			(xy 393.7 198.12) (xy 398.78 198.12)
		)
		(stroke
			(width 0)
			(type default)
		)
	)
	(wire
		(pts
			(xy 303.53 127) (xy 320.04 127)
		)
		(stroke
			(width 0)
			(type default)
		)
	)
	(wire
		(pts
			(xy 115.57 71.12) (xy 113.03 71.12)
		)
		(stroke
			(width 0)
			(type default)
		)
	)
	(wire
		(pts
			(xy 44.45 81.28) (xy 44.45 82.55)
		)
		(stroke
			(width 0)
			(type default)
		)
	)
	(wire
		(pts
			(xy 398.78 167.64) (xy 398.78 172.72)
		)
		(stroke
			(width 0)
			(type default)
		)
	)
	(wire
		(pts
			(xy 312.42 166.37) (xy 312.42 168.91)
		)
		(stroke
			(width 0)
			(type default)
		)
	)
	(wire
		(pts
			(xy 110.49 196.85) (xy 121.92 196.85)
		)
		(stroke
			(width 0)
			(type default)
		)
	)
	(wire
		(pts
			(xy 224.79 144.78) (xy 199.39 144.78)
		)
		(stroke
			(width 0)
			(type default)
		)
	)
	(wire
		(pts
			(xy 295.91 173.99) (xy 295.91 179.07)
		)
		(stroke
			(width 0)
			(type default)
		)
	)
	(wire
		(pts
			(xy 331.47 71.12) (xy 359.41 71.12)
		)
		(stroke
			(width 0)
			(type default)
		)
	)
	(wire
		(pts
			(xy 44.45 88.9) (xy 52.07 88.9)
		)
		(stroke
			(width 0)
			(type default)
		)
	)
	(wire
		(pts
			(xy 295.91 116.84) (xy 303.53 116.84)
		)
		(stroke
			(width 0)
			(type default)
		)
	)
	(wire
		(pts
			(xy 317.5 50.8) (xy 317.5 43.18)
		)
		(stroke
			(width 0)
			(type default)
		)
	)
	(wire
		(pts
			(xy 393.7 167.64) (xy 398.78 167.64)
		)
		(stroke
			(width 0)
			(type default)
		)
	)
	(wire
		(pts
			(xy 331.47 106.68) (xy 359.41 106.68)
		)
		(stroke
			(width 0)
			(type default)
		)
	)
	(polyline
		(pts
			(xy 231.14 205.74) (xy 231.14 284.48)
		)
		(stroke
			(width 0)
			(type default)
		)
	)
	(polyline
		(pts
			(xy 90.17 118.11) (xy 90.17 205.74)
		)
		(stroke
			(width 0)
			(type default)
		)
	)
	(wire
		(pts
			(xy 246.38 179.07) (xy 257.81 179.07)
		)
		(stroke
			(width 0)
			(type default)
		)
	)
	(wire
		(pts
			(xy 292.1 73.66) (xy 320.04 73.66)
		)
		(stroke
			(width 0)
			(type default)
		)
	)
	(wire
		(pts
			(xy 173.99 86.36) (xy 191.77 86.36)
		)
		(stroke
			(width 0)
			(type default)
		)
	)
	(wire
		(pts
			(xy 320.04 50.8) (xy 317.5 50.8)
		)
		(stroke
			(width 0)
			(type default)
		)
	)
	(wire
		(pts
			(xy 342.9 63.5) (xy 331.47 63.5)
		)
		(stroke
			(width 0)
			(type default)
		)
	)
	(wire
		(pts
			(xy 140.97 255.27) (xy 140.97 254)
		)
		(stroke
			(width 0)
			(type default)
		)
	)
	(wire
		(pts
			(xy 342.9 66.04) (xy 331.47 66.04)
		)
		(stroke
			(width 0)
			(type default)
		)
	)
	(wire
		(pts
			(xy 55.88 87.63) (xy 55.88 88.9)
		)
		(stroke
			(width 0)
			(type default)
		)
	)
	(wire
		(pts
			(xy 147.32 50.8) (xy 162.56 50.8)
		)
		(stroke
			(width 0)
			(type default)
		)
	)
	(wire
		(pts
			(xy 292.1 76.2) (xy 320.04 76.2)
		)
		(stroke
			(width 0)
			(type default)
		)
	)
	(wire
		(pts
			(xy 109.22 140.97) (xy 121.92 140.97)
		)
		(stroke
			(width 0)
			(type default)
		)
	)
	(wire
		(pts
			(xy 292.1 93.98) (xy 320.04 93.98)
		)
		(stroke
			(width 0)
			(type default)
		)
	)
	(wire
		(pts
			(xy 281.94 45.72) (xy 320.04 45.72)
		)
		(stroke
			(width 0)
			(type default)
		)
	)
	(wire
		(pts
			(xy 187.96 53.34) (xy 189.23 53.34)
		)
		(stroke
			(width 0)
			(type default)
		)
	)
	(wire
		(pts
			(xy 246.38 179.07) (xy 246.38 180.34)
		)
		(stroke
			(width 0)
			(type default)
		)
	)
	(wire
		(pts
			(xy 154.94 173.99) (xy 132.08 173.99)
		)
		(stroke
			(width 0)
			(type default)
		)
	)
	(wire
		(pts
			(xy 279.4 185.42) (xy 279.4 186.69)
		)
		(stroke
			(width 0)
			(type default)
		)
	)
	(wire
		(pts
			(xy 88.9 257.81) (xy 93.98 257.81)
		)
		(stroke
			(width 0)
			(type default)
		)
	)
	(wire
		(pts
			(xy 334.01 68.58) (xy 334.01 81.28)
		)
		(stroke
			(width 0)
			(type default)
		)
	)
	(wire
		(pts
			(xy 334.01 124.46) (xy 334.01 129.54)
		)
		(stroke
			(width 0)
			(type default)
		)
	)
	(wire
		(pts
			(xy 265.43 232.41) (xy 261.62 232.41)
		)
		(stroke
			(width 0)
			(type default)
		)
	)
	(wire
		(pts
			(xy 292.1 99.06) (xy 320.04 99.06)
		)
		(stroke
			(width 0)
			(type default)
		)
	)
	(wire
		(pts
			(xy 57.15 54.61) (xy 67.31 54.61)
		)
		(stroke
			(width 0)
			(type default)
		)
	)
	(wire
		(pts
			(xy 267.97 274.32) (xy 267.97 275.59)
		)
		(stroke
			(width 0)
			(type default)
		)
	)
	(wire
		(pts
			(xy 331.47 86.36) (xy 359.41 86.36)
		)
		(stroke
			(width 0)
			(type default)
		)
	)
	(wire
		(pts
			(xy 331.47 93.98) (xy 359.41 93.98)
		)
		(stroke
			(width 0)
			(type default)
		)
	)
	(wire
		(pts
			(xy 308.61 116.84) (xy 320.04 116.84)
		)
		(stroke
			(width 0)
			(type default)
		)
	)
	(wire
		(pts
			(xy 372.11 218.44) (xy 388.62 218.44)
		)
		(stroke
			(width 0)
			(type default)
		)
	)
	(wire
		(pts
			(xy 115.57 68.58) (xy 113.03 68.58)
		)
		(stroke
			(width 0)
			(type default)
		)
	)
	(wire
		(pts
			(xy 110.49 194.31) (xy 121.92 194.31)
		)
		(stroke
			(width 0)
			(type default)
		)
	)
	(wire
		(pts
			(xy 292.1 78.74) (xy 320.04 78.74)
		)
		(stroke
			(width 0)
			(type default)
		)
	)
	(wire
		(pts
			(xy 320.04 119.38) (xy 314.96 119.38)
		)
		(stroke
			(width 0)
			(type default)
		)
	)
	(wire
		(pts
			(xy 284.48 88.9) (xy 320.04 88.9)
		)
		(stroke
			(width 0)
			(type default)
		)
	)
	(wire
		(pts
			(xy 138.43 251.46) (xy 140.97 251.46)
		)
		(stroke
			(width 0)
			(type default)
		)
	)
	(wire
		(pts
			(xy 271.78 63.5) (xy 280.67 63.5)
		)
		(stroke
			(width 0)
			(type default)
		)
	)
	(wire
		(pts
			(xy 140.97 254) (xy 143.51 254)
		)
		(stroke
			(width 0)
			(type default)
		)
	)
	(wire
		(pts
			(xy 331.47 88.9) (xy 359.41 88.9)
		)
		(stroke
			(width 0)
			(type default)
		)
	)
	(wire
		(pts
			(xy 398.78 182.88) (xy 398.78 177.8)
		)
		(stroke
			(width 0)
			(type default)
		)
	)
	(wire
		(pts
			(xy 393.7 238.76) (xy 398.78 238.76)
		)
		(stroke
			(width 0)
			(type default)
		)
	)
	(wire
		(pts
			(xy 336.55 134.62) (xy 331.47 134.62)
		)
		(stroke
			(width 0)
			(type default)
		)
	)
	(wire
		(pts
			(xy 317.5 111.76) (xy 320.04 111.76)
		)
		(stroke
			(width 0)
			(type default)
		)
	)
	(wire
		(pts
			(xy 217.17 92.71) (xy 217.17 91.44)
		)
		(stroke
			(width 0)
			(type default)
		)
	)
	(wire
		(pts
			(xy 115.57 78.74) (xy 113.03 78.74)
		)
		(stroke
			(width 0)
			(type default)
		)
	)
	(wire
		(pts
			(xy 224.79 191.77) (xy 199.39 191.77)
		)
		(stroke
			(width 0)
			(type default)
		)
	)
	(wire
		(pts
			(xy 331.47 127) (xy 353.06 127)
		)
		(stroke
			(width 0)
			(type default)
		)
	)
	(wire
		(pts
			(xy 393.7 162.56) (xy 398.78 162.56)
		)
		(stroke
			(width 0)
			(type default)
		)
	)
	(wire
		(pts
			(xy 68.58 63.5) (xy 67.31 63.5)
		)
		(stroke
			(width 0)
			(type default)
		)
	)
	(wire
		(pts
			(xy 285.75 63.5) (xy 320.04 63.5)
		)
		(stroke
			(width 0)
			(type default)
		)
	)
	(wire
		(pts
			(xy 218.44 83.82) (xy 214.63 83.82)
		)
		(stroke
			(width 0)
			(type default)
		)
	)
	(wire
		(pts
			(xy 331.47 40.64) (xy 342.9 40.64)
		)
		(stroke
			(width 0)
			(type default)
		)
	)
	(wire
		(pts
			(xy 199.39 255.27) (xy 199.39 254)
		)
		(stroke
			(width 0)
			(type default)
		)
	)
	(wire
		(pts
			(xy 331.47 101.6) (xy 359.41 101.6)
		)
		(stroke
			(width 0)
			(type default)
		)
	)
	(wire
		(pts
			(xy 393.7 187.96) (xy 398.78 187.96)
		)
		(stroke
			(width 0)
			(type default)
		)
	)
	(wire
		(pts
			(xy 224.79 137.16) (xy 199.39 137.16)
		)
		(stroke
			(width 0)
			(type default)
		)
	)
	(wire
		(pts
			(xy 317.5 81.28) (xy 317.5 96.52)
		)
		(stroke
			(width 0)
			(type default)
		)
	)
	(wire
		(pts
			(xy 177.8 173.99) (xy 189.23 173.99)
		)
		(stroke
			(width 0)
			(type default)
		)
	)
	(wire
		(pts
			(xy 267.97 232.41) (xy 270.51 232.41)
		)
		(stroke
			(width 0)
			(type default)
		)
	)
	(wire
		(pts
			(xy 34.29 163.83) (xy 34.29 149.86)
		)
		(stroke
			(width 0)
			(type default)
		)
	)
	(wire
		(pts
			(xy 261.62 241.3) (xy 261.62 245.11)
		)
		(stroke
			(width 0)
			(type default)
		)
	)
	(wire
		(pts
			(xy 208.28 238.76) (xy 208.28 240.03)
		)
		(stroke
			(width 0)
			(type default)
		)
	)
	(wire
		(pts
			(xy 331.47 132.08) (xy 336.55 132.08)
		)
		(stroke
			(width 0)
			(type default)
		)
	)
	(wire
		(pts
			(xy 295.91 179.07) (xy 295.91 180.34)
		)
		(stroke
			(width 0)
			(type default)
		)
	)
	(wire
		(pts
			(xy 331.47 96.52) (xy 334.01 96.52)
		)
		(stroke
			(width 0)
			(type default)
		)
	)
	(wire
		(pts
			(xy 261.62 261.62) (xy 261.62 265.43)
		)
		(stroke
			(width 0)
			(type default)
		)
	)
	(wire
		(pts
			(xy 224.79 158.75) (xy 199.39 158.75)
		)
		(stroke
			(width 0)
			(type default)
		)
	)
	(wire
		(pts
			(xy 208.28 232.41) (xy 208.28 233.68)
		)
		(stroke
			(width 0)
			(type default)
		)
	)
	(wire
		(pts
			(xy 393.7 203.2) (xy 398.78 203.2)
		)
		(stroke
			(width 0)
			(type default)
		)
	)
	(wire
		(pts
			(xy 398.78 213.36) (xy 398.78 218.44)
		)
		(stroke
			(width 0)
			(type default)
		)
	)
	(wire
		(pts
			(xy 320.04 58.42) (xy 317.5 58.42)
		)
		(stroke
			(width 0)
			(type default)
		)
	)
	(wire
		(pts
			(xy 196.85 251.46) (xy 199.39 251.46)
		)
		(stroke
			(width 0)
			(type default)
		)
	)
	(wire
		(pts
			(xy 57.15 171.45) (xy 55.88 171.45)
		)
		(stroke
			(width 0)
			(type default)
		)
	)
	(wire
		(pts
			(xy 262.89 179.07) (xy 262.89 180.34)
		)
		(stroke
			(width 0)
			(type default)
		)
	)
	(wire
		(pts
			(xy 349.25 119.38) (xy 359.41 119.38)
		)
		(stroke
			(width 0)
			(type default)
		)
	)
	(wire
		(pts
			(xy 372.11 203.2) (xy 388.62 203.2)
		)
		(stroke
			(width 0)
			(type default)
		)
	)
	(wire
		(pts
			(xy 185.42 88.9) (xy 218.44 88.9)
		)
		(stroke
			(width 0)
			(type default)
		)
	)
	(wire
		(pts
			(xy 90.17 83.82) (xy 90.17 85.09)
		)
		(stroke
			(width 0)
			(type default)
		)
	)
	(wire
		(pts
			(xy 29.21 148.59) (xy 29.21 149.86)
		)
		(stroke
			(width 0)
			(type default)
		)
	)
	(wire
		(pts
			(xy 88.9 262.89) (xy 92.71 262.89)
		)
		(stroke
			(width 0)
			(type default)
		)
	)
	(wire
		(pts
			(xy 312.42 185.42) (xy 312.42 186.69)
		)
		(stroke
			(width 0)
			(type default)
		)
	)
	(wire
		(pts
			(xy 149.86 256.54) (xy 149.86 261.62)
		)
		(stroke
			(width 0)
			(type default)
		)
	)
	(wire
		(pts
			(xy 317.5 96.52) (xy 320.04 96.52)
		)
		(stroke
			(width 0)
			(type default)
		)
	)
	(wire
		(pts
			(xy 262.89 185.42) (xy 262.89 186.69)
		)
		(stroke
			(width 0)
			(type default)
		)
	)
	(wire
		(pts
			(xy 303.53 121.92) (xy 314.96 121.92)
		)
		(stroke
			(width 0)
			(type default)
		)
	)
	(wire
		(pts
			(xy 175.26 194.31) (xy 189.23 194.31)
		)
		(stroke
			(width 0)
			(type default)
		)
	)
	(wire
		(pts
			(xy 331.47 129.54) (xy 334.01 129.54)
		)
		(stroke
			(width 0)
			(type default)
		)
	)
	(wire
		(pts
			(xy 173.99 158.75) (xy 189.23 158.75)
		)
		(stroke
			(width 0)
			(type default)
		)
	)
	(wire
		(pts
			(xy 97.79 240.03) (xy 99.06 240.03)
		)
		(stroke
			(width 0)
			(type default)
		)
	)
	(wire
		(pts
			(xy 292.1 91.44) (xy 320.04 91.44)
		)
		(stroke
			(width 0)
			(type default)
		)
	)
	(wire
		(pts
			(xy 55.88 168.91) (xy 76.2 168.91)
		)
		(stroke
			(width 0)
			(type default)
		)
	)
	(wire
		(pts
			(xy 204.47 45.72) (xy 204.47 49.53)
		)
		(stroke
			(width 0)
			(type default)
		)
	)
	(wire
		(pts
			(xy 116.84 143.51) (xy 121.92 143.51)
		)
		(stroke
			(width 0)
			(type default)
		)
	)
	(wire
		(pts
			(xy 204.47 60.96) (xy 204.47 62.23)
		)
		(stroke
			(width 0)
			(type default)
		)
	)
	(wire
		(pts
			(xy 331.47 68.58) (xy 334.01 68.58)
		)
		(stroke
			(width 0)
			(type default)
		)
	)
	(wire
		(pts
			(xy 320.04 35.56) (xy 317.5 35.56)
		)
		(stroke
			(width 0)
			(type default)
		)
	)
	(wire
		(pts
			(xy 393.7 208.28) (xy 398.78 208.28)
		)
		(stroke
			(width 0)
			(type default)
		)
	)
	(wire
		(pts
			(xy 393.7 177.8) (xy 398.78 177.8)
		)
		(stroke
			(width 0)
			(type default)
		)
	)
	(wire
		(pts
			(xy 284.48 86.36) (xy 320.04 86.36)
		)
		(stroke
			(width 0)
			(type default)
		)
	)
	(wire
		(pts
			(xy 271.78 53.34) (xy 320.04 53.34)
		)
		(stroke
			(width 0)
			(type default)
		)
	)
	(wire
		(pts
			(xy 262.89 179.07) (xy 274.32 179.07)
		)
		(stroke
			(width 0)
			(type default)
		)
	)
	(wire
		(pts
			(xy 149.86 238.76) (xy 149.86 240.03)
		)
		(stroke
			(width 0)
			(type default)
		)
	)
	(wire
		(pts
			(xy 344.17 121.92) (xy 331.47 121.92)
		)
		(stroke
			(width 0)
			(type default)
		)
	)
	(wire
		(pts
			(xy 39.37 234.95) (xy 45.72 234.95)
		)
		(stroke
			(width 0)
			(type default)
		)
	)
	(wire
		(pts
			(xy 52.07 88.9) (xy 52.07 77.47)
		)
		(stroke
			(width 0)
			(type default)
		)
	)
	(wire
		(pts
			(xy 331.47 109.22) (xy 359.41 109.22)
		)
		(stroke
			(width 0)
			(type default)
		)
	)
	(wire
		(pts
			(xy 349.25 121.92) (xy 359.41 121.92)
		)
		(stroke
			(width 0)
			(type default)
		)
	)
	(wire
		(pts
			(xy 261.62 270.51) (xy 261.62 274.32)
		)
		(stroke
			(width 0)
			(type default)
		)
	)
	(wire
		(pts
			(xy 88.9 60.96) (xy 102.87 60.96)
		)
		(stroke
			(width 0)
			(type default)
		)
	)
	(wire
		(pts
			(xy 113.03 146.05) (xy 121.92 146.05)
		)
		(stroke
			(width 0)
			(type default)
		)
	)
	(wire
		(pts
			(xy 265.43 261.62) (xy 265.43 262.89)
		)
		(stroke
			(width 0)
			(type default)
		)
	)
	(wire
		(pts
			(xy 393.7 182.88) (xy 398.78 182.88)
		)
		(stroke
			(width 0)
			(type default)
		)
	)
	(wire
		(pts
			(xy 398.78 187.96) (xy 398.78 193.04)
		)
		(stroke
			(width 0)
			(type default)
		)
	)
	(wire
		(pts
			(xy 76.2 234.95) (xy 74.93 234.95)
		)
		(stroke
			(width 0)
			(type default)
		)
	)
	(wire
		(pts
			(xy 181.61 144.78) (xy 189.23 144.78)
		)
		(stroke
			(width 0)
			(type default)
		)
	)
	(wire
		(pts
			(xy 261.62 224.79) (xy 261.62 226.06)
		)
		(stroke
			(width 0)
			(type default)
		)
	)
	(wire
		(pts
			(xy 292.1 71.12) (xy 320.04 71.12)
		)
		(stroke
			(width 0)
			(type default)
		)
	)
	(wire
		(pts
			(xy 36.83 232.41) (xy 45.72 232.41)
		)
		(stroke
			(width 0)
			(type default)
		)
	)
	(wire
		(pts
			(xy 29.21 156.21) (xy 29.21 158.75)
		)
		(stroke
			(width 0)
			(type default)
		)
	)
	(wire
		(pts
			(xy 267.97 232.41) (xy 267.97 233.68)
		)
		(stroke
			(width 0)
			(type default)
		)
	)
	(wire
		(pts
			(xy 317.5 124.46) (xy 320.04 124.46)
		)
		(stroke
			(width 0)
			(type default)
		)
	)
	(wire
		(pts
			(xy 97.79 234.95) (xy 99.06 234.95)
		)
		(stroke
			(width 0)
			(type default)
		)
	)
	(wire
		(pts
			(xy 111.76 173.99) (xy 121.92 173.99)
		)
		(stroke
			(width 0)
			(type default)
		)
	)
	(wire
		(pts
			(xy 73.66 148.59) (xy 73.66 171.45)
		)
		(stroke
			(width 0)
			(type default)
		)
	)
	(wire
		(pts
			(xy 372.11 187.96) (xy 388.62 187.96)
		)
		(stroke
			(width 0)
			(type default)
		)
	)
	(wire
		(pts
			(xy 74.93 242.57) (xy 81.28 242.57)
		)
		(stroke
			(width 0)
			(type default)
		)
	)
	(wire
		(pts
			(xy 224.79 179.07) (xy 199.39 179.07)
		)
		(stroke
			(width 0)
			(type default)
		)
	)
	(wire
		(pts
			(xy 162.56 50.8) (xy 172.72 50.8)
		)
		(stroke
			(width 0)
			(type default)
		)
	)
	(wire
		(pts
			(xy 67.31 60.96) (xy 68.58 60.96)
		)
		(stroke
			(width 0)
			(type default)
		)
	)
	(wire
		(pts
			(xy 154.94 138.43) (xy 132.08 138.43)
		)
		(stroke
			(width 0)
			(type default)
		)
	)
	(wire
		(pts
			(xy 88.9 260.35) (xy 92.71 260.35)
		)
		(stroke
			(width 0)
			(type default)
		)
	)
	(wire
		(pts
			(xy 312.42 173.99) (xy 312.42 179.07)
		)
		(stroke
			(width 0)
			(type default)
		)
	)
	(wire
		(pts
			(xy 82.55 232.41) (xy 87.63 232.41)
		)
		(stroke
			(width 0)
			(type default)
		)
	)
	(wire
		(pts
			(xy 261.62 254) (xy 261.62 255.27)
		)
		(stroke
			(width 0)
			(type default)
		)
	)
	(wire
		(pts
			(xy 393.7 193.04) (xy 398.78 193.04)
		)
		(stroke
			(width 0)
			(type default)
		)
	)
	(wire
		(pts
			(xy 34.29 171.45) (xy 34.29 163.83)
		)
		(stroke
			(width 0)
			(type default)
		)
	)
	(wire
		(pts
			(xy 328.93 240.03) (xy 331.47 240.03)
		)
		(stroke
			(width 0)
			(type default)
		)
	)
	(wire
		(pts
			(xy 285.75 48.26) (xy 320.04 48.26)
		)
		(stroke
			(width 0)
			(type default)
		)
	)
	(wire
		(pts
			(xy 398.78 193.04) (xy 398.78 198.12)
		)
		(stroke
			(width 0)
			(type default)
		)
	)
	(wire
		(pts
			(xy 398.78 223.52) (xy 398.78 228.6)
		)
		(stroke
			(width 0)
			(type default)
		)
	)
	(wire
		(pts
			(xy 208.28 245.11) (xy 208.28 246.38)
		)
		(stroke
			(width 0)
			(type default)
		)
	)
	(wire
		(pts
			(xy 279.4 179.07) (xy 279.4 180.34)
		)
		(stroke
			(width 0)
			(type default)
		)
	)
	(wire
		(pts
			(xy 199.39 260.35) (xy 199.39 261.62)
		)
		(stroke
			(width 0)
			(type default)
		)
	)
	(wire
		(pts
			(xy 393.7 243.84) (xy 398.78 243.84)
		)
		(stroke
			(width 0)
			(type default)
		)
	)
	(wire
		(pts
			(xy 53.34 257.81) (xy 63.5 257.81)
		)
		(stroke
			(width 0)
			(type default)
		)
	)
	(wire
		(pts
			(xy 217.17 91.44) (xy 218.44 91.44)
		)
		(stroke
			(width 0)
			(type default)
		)
	)
	(wire
		(pts
			(xy 187.96 48.26) (xy 194.31 48.26)
		)
		(stroke
			(width 0)
			(type default)
		)
	)
	(wire
		(pts
			(xy 292.1 106.68) (xy 320.04 106.68)
		)
		(stroke
			(width 0)
			(type default)
		)
	)
	(wire
		(pts
			(xy 38.1 67.31) (xy 44.45 67.31)
		)
		(stroke
			(width 0)
			(type default)
		)
	)
	(wire
		(pts
			(xy 173.99 161.29) (xy 189.23 161.29)
		)
		(stroke
			(width 0)
			(type default)
		)
	)
	(wire
		(pts
			(xy 334.01 111.76) (xy 334.01 124.46)
		)
		(stroke
			(width 0)
			(type default)
		)
	)
	(wire
		(pts
			(xy 331.47 78.74) (xy 359.41 78.74)
		)
		(stroke
			(width 0)
			(type default)
		)
	)
	(wire
		(pts
			(xy 372.11 162.56) (xy 388.62 162.56)
		)
		(stroke
			(width 0)
			(type default)
		)
	)
	(wire
		(pts
			(xy 92.71 262.89) (xy 92.71 260.35)
		)
		(stroke
			(width 0)
			(type default)
		)
	)
	(wire
		(pts
			(xy 271.78 48.26) (xy 280.67 48.26)
		)
		(stroke
			(width 0)
			(type default)
		)
	)
	(wire
		(pts
			(xy 334.01 81.28) (xy 334.01 96.52)
		)
		(stroke
			(width 0)
			(type default)
		)
	)
	(wire
		(pts
			(xy 331.47 104.14) (xy 359.41 104.14)
		)
		(stroke
			(width 0)
			(type default)
		)
	)
	(wire
		(pts
			(xy 73.66 171.45) (xy 76.2 171.45)
		)
		(stroke
			(width 0)
			(type default)
		)
	)
	(wire
		(pts
			(xy 44.45 67.31) (xy 68.58 67.31)
		)
		(stroke
			(width 0)
			(type default)
		)
	)
	(wire
		(pts
			(xy 224.79 161.29) (xy 199.39 161.29)
		)
		(stroke
			(width 0)
			(type default)
		)
	)
	(wire
		(pts
			(xy 295.91 114.3) (xy 303.53 114.3)
		)
		(stroke
			(width 0)
			(type default)
		)
	)
	(wire
		(pts
			(xy 267.97 274.32) (xy 267.97 273.05)
		)
		(stroke
			(width 0)
			(type default)
		)
	)
	(wire
		(pts
			(xy 185.42 96.52) (xy 185.42 97.79)
		)
		(stroke
			(width 0)
			(type default)
		)
	)
	(wire
		(pts
			(xy 331.47 43.18) (xy 342.9 43.18)
		)
		(stroke
			(width 0)
			(type default)
		)
	)
	(wire
		(pts
			(xy 88.9 68.58) (xy 102.87 68.58)
		)
		(stroke
			(width 0)
			(type default)
		)
	)
	(wire
		(pts
			(xy 171.45 45.72) (xy 171.45 34.29)
		)
		(stroke
			(width 0)
			(type default)
		)
	)
	(polyline
		(pts
			(xy 144.78 12.7) (xy 144.78 118.11)
		)
		(stroke
			(width 0)
			(type default)
		)
	)
	(wire
		(pts
			(xy 354.33 177.8) (xy 388.62 177.8)
		)
		(stroke
			(width 0)
			(type default)
		)
	)
	(wire
		(pts
			(xy 334.01 96.52) (xy 334.01 111.76)
		)
		(stroke
			(width 0)
			(type default)
		)
	)
	(wire
		(pts
			(xy 44.45 87.63) (xy 44.45 88.9)
		)
		(stroke
			(width 0)
			(type default)
		)
	)
	(wire
		(pts
			(xy 265.43 261.62) (xy 261.62 261.62)
		)
		(stroke
			(width 0)
			(type default)
		)
	)
	(wire
		(pts
			(xy 82.55 237.49) (xy 87.63 237.49)
		)
		(stroke
			(width 0)
			(type default)
		)
	)
	(wire
		(pts
			(xy 372.11 157.48) (xy 388.62 157.48)
		)
		(stroke
			(width 0)
			(type default)
		)
	)
	(wire
		(pts
			(xy 44.45 237.49) (xy 44.45 242.57)
		)
		(stroke
			(width 0)
			(type default)
		)
	)
	(wire
		(pts
			(xy 349.25 114.3) (xy 359.41 114.3)
		)
		(stroke
			(width 0)
			(type default)
		)
	)
	(polyline
		(pts
			(xy 118.11 205.74) (xy 118.11 283.21)
		)
		(stroke
			(width 0)
			(type default)
		)
	)
	(wire
		(pts
			(xy 331.47 58.42) (xy 342.9 58.42)
		)
		(stroke
			(width 0)
			(type default)
		)
	)
	(wire
		(pts
			(xy 393.7 213.36) (xy 398.78 213.36)
		)
		(stroke
			(width 0)
			(type default)
		)
	)
	(wire
		(pts
			(xy 393.7 228.6) (xy 398.78 228.6)
		)
		(stroke
			(width 0)
			(type default)
		)
	)
	(wire
		(pts
			(xy 34.29 163.83) (xy 35.56 163.83)
		)
		(stroke
			(width 0)
			(type default)
		)
	)
	(wire
		(pts
			(xy 33.02 166.37) (xy 35.56 166.37)
		)
		(stroke
			(width 0)
			(type default)
		)
	)
	(wire
		(pts
			(xy 320.04 129.54) (xy 317.5 129.54)
		)
		(stroke
			(width 0)
			(type default)
		)
	)
	(wire
		(pts
			(xy 331.47 50.8) (xy 342.9 50.8)
		)
		(stroke
			(width 0)
			(type default)
		)
	)
	(wire
		(pts
			(xy 372.11 233.68) (xy 388.62 233.68)
		)
		(stroke
			(width 0)
			(type default)
		)
	)
	(wire
		(pts
			(xy 46.99 71.12) (xy 68.58 71.12)
		)
		(stroke
			(width 0)
			(type default)
		)
	)
	(wire
		(pts
			(xy 34.29 149.86) (xy 29.21 149.86)
		)
		(stroke
			(width 0)
			(type default)
		)
	)
	(wire
		(pts
			(xy 185.42 91.44) (xy 185.42 88.9)
		)
		(stroke
			(width 0)
			(type default)
		)
	)
	(wire
		(pts
			(xy 88.9 63.5) (xy 102.87 63.5)
		)
		(stroke
			(width 0)
			(type default)
		)
	)
	(wire
		(pts
			(xy 328.93 234.95) (xy 331.47 234.95)
		)
		(stroke
			(width 0)
			(type default)
		)
	)
	(wire
		(pts
			(xy 265.43 232.41) (xy 267.97 232.41)
		)
		(stroke
			(width 0)
			(type default)
		)
	)
	(wire
		(pts
			(xy 398.78 228.6) (xy 398.78 233.68)
		)
		(stroke
			(width 0)
			(type default)
		)
	)
	(wire
		(pts
			(xy 214.63 45.72) (xy 214.63 83.82)
		)
		(stroke
			(width 0)
			(type default)
		)
	)
	(polyline
		(pts
			(xy 12.7 118.11) (xy 199.39 118.11)
		)
		(stroke
			(width 0)
			(type default)
		)
	)
	(wire
		(pts
			(xy 76.2 234.95) (xy 76.2 247.65)
		)
		(stroke
			(width 0)
			(type default)
		)
	)
	(wire
		(pts
			(xy 334.01 129.54) (xy 334.01 137.16)
		)
		(stroke
			(width 0)
			(type default)
		)
	)
	(wire
		(pts
			(xy 398.78 213.36) (xy 398.78 208.28)
		)
		(stroke
			(width 0)
			(type default)
		)
	)
	(wire
		(pts
			(xy 314.96 132.08) (xy 320.04 132.08)
		)
		(stroke
			(width 0)
			(type default)
		)
	)
	(wire
		(pts
			(xy 181.61 142.24) (xy 189.23 142.24)
		)
		(stroke
			(width 0)
			(type default)
		)
	)
	(wire
		(pts
			(xy 317.5 111.76) (xy 317.5 124.46)
		)
		(stroke
			(width 0)
			(type default)
		)
	)
	(wire
		(pts
			(xy 331.47 124.46) (xy 334.01 124.46)
		)
		(stroke
			(width 0)
			(type default)
		)
	)
	(wire
		(pts
			(xy 295.91 185.42) (xy 295.91 186.69)
		)
		(stroke
			(width 0)
			(type default)
		)
	)
	(polyline
		(pts
			(xy 299.72 205.74) (xy 231.14 205.74)
		)
		(stroke
			(width 0)
			(type default)
		)
	)
	(wire
		(pts
			(xy 224.79 176.53) (xy 199.39 176.53)
		)
		(stroke
			(width 0)
			(type default)
		)
	)
	(wire
		(pts
			(xy 88.9 78.74) (xy 102.87 78.74)
		)
		(stroke
			(width 0)
			(type default)
		)
	)
	(wire
		(pts
			(xy 331.47 81.28) (xy 334.01 81.28)
		)
		(stroke
			(width 0)
			(type default)
		)
	)
	(wire
		(pts
			(xy 154.94 156.21) (xy 132.08 156.21)
		)
		(stroke
			(width 0)
			(type default)
		)
	)
	(wire
		(pts
			(xy 398.78 233.68) (xy 398.78 238.76)
		)
		(stroke
			(width 0)
			(type default)
		)
	)
	(wire
		(pts
			(xy 154.94 140.97) (xy 132.08 140.97)
		)
		(stroke
			(width 0)
			(type default)
		)
	)
	(wire
		(pts
			(xy 398.78 182.88) (xy 398.78 187.96)
		)
		(stroke
			(width 0)
			(type default)
		)
	)
	(wire
		(pts
			(xy 92.71 260.35) (xy 93.98 260.35)
		)
		(stroke
			(width 0)
			(type default)
		)
	)
	(wire
		(pts
			(xy 181.61 137.16) (xy 189.23 137.16)
		)
		(stroke
			(width 0)
			(type default)
		)
	)
	(wire
		(pts
			(xy 292.1 68.58) (xy 320.04 68.58)
		)
		(stroke
			(width 0)
			(type default)
		)
	)
	(wire
		(pts
			(xy 224.79 142.24) (xy 199.39 142.24)
		)
		(stroke
			(width 0)
			(type default)
		)
	)
	(wire
		(pts
			(xy 217.17 81.28) (xy 217.17 91.44)
		)
		(stroke
			(width 0)
			(type default)
		)
	)
	(wire
		(pts
			(xy 265.43 245.11) (xy 267.97 245.11)
		)
		(stroke
			(width 0)
			(type default)
		)
	)
	(wire
		(pts
			(xy 67.31 63.5) (xy 67.31 60.96)
		)
		(stroke
			(width 0)
			(type default)
		)
	)
	(wire
		(pts
			(xy 217.17 81.28) (xy 218.44 81.28)
		)
		(stroke
			(width 0)
			(type default)
		)
	)
	(wire
		(pts
			(xy 331.47 55.88) (xy 342.9 55.88)
		)
		(stroke
			(width 0)
			(type default)
		)
	)
	(wire
		(pts
			(xy 398.78 157.48) (xy 398.78 162.56)
		)
		(stroke
			(width 0)
			(type default)
		)
	)
	(wire
		(pts
			(xy 398.78 218.44) (xy 398.78 223.52)
		)
		(stroke
			(width 0)
			(type default)
		)
	)
	(wire
		(pts
			(xy 393.7 223.52) (xy 398.78 223.52)
		)
		(stroke
			(width 0)
			(type default)
		)
	)
	(wire
		(pts
			(xy 224.79 173.99) (xy 199.39 173.99)
		)
		(stroke
			(width 0)
			(type default)
		)
	)
	(wire
		(pts
			(xy 73.66 173.99) (xy 76.2 173.99)
		)
		(stroke
			(width 0)
			(type default)
		)
	)
	(wire
		(pts
			(xy 261.62 231.14) (xy 261.62 232.41)
		)
		(stroke
			(width 0)
			(type default)
		)
	)
	(wire
		(pts
			(xy 262.89 173.99) (xy 262.89 179.07)
		)
		(stroke
			(width 0)
			(type default)
		)
	)
	(wire
		(pts
			(xy 331.47 45.72) (xy 334.01 45.72)
		)
		(stroke
			(width 0)
			(type default)
		)
	)
	(wire
		(pts
			(xy 312.42 179.07) (xy 312.42 180.34)
		)
		(stroke
			(width 0)
			(type default)
		)
	)
	(wire
		(pts
			(xy 334.01 45.72) (xy 334.01 53.34)
		)
		(stroke
			(width 0)
			(type default)
		)
	)
	(polyline
		(pts
			(xy 118.11 205.74) (xy 231.14 205.74)
		)
		(stroke
			(width 0)
			(type default)
		)
	)
	(wire
		(pts
			(xy 331.47 73.66) (xy 359.41 73.66)
		)
		(stroke
			(width 0)
			(type default)
		)
	)
	(wire
		(pts
			(xy 271.78 55.88) (xy 320.04 55.88)
		)
		(stroke
			(width 0)
			(type default)
		)
	)
	(wire
		(pts
			(xy 292.1 104.14) (xy 320.04 104.14)
		)
		(stroke
			(width 0)
			(type default)
		)
	)
	(wire
		(pts
			(xy 154.94 146.05) (xy 132.08 146.05)
		)
		(stroke
			(width 0)
			(type default)
		)
	)
	(wire
		(pts
			(xy 393.7 157.48) (xy 398.78 157.48)
		)
		(stroke
			(width 0)
			(type default)
		)
	)
	(wire
		(pts
			(xy 55.88 163.83) (xy 57.15 163.83)
		)
		(stroke
			(width 0)
			(type default)
		)
	)
	(wire
		(pts
			(xy 317.5 35.56) (xy 317.5 43.18)
		)
		(stroke
			(width 0)
			(type default)
		)
	)
	(wire
		(pts
			(xy 154.94 194.31) (xy 132.08 194.31)
		)
		(stroke
			(width 0)
			(type default)
		)
	)
	(wire
		(pts
			(xy 246.38 173.99) (xy 246.38 179.07)
		)
		(stroke
			(width 0)
			(type default)
		)
	)
	(wire
		(pts
			(xy 314.96 134.62) (xy 320.04 134.62)
		)
		(stroke
			(width 0)
			(type default)
		)
	)
	(wire
		(pts
			(xy 344.17 114.3) (xy 331.47 114.3)
		)
		(stroke
			(width 0)
			(type default)
		)
	)
	(wire
		(pts
			(xy 336.55 132.08) (xy 347.98 132.08)
		)
		(stroke
			(width 0)
			(type default)
		)
	)
	(wire
		(pts
			(xy 187.96 45.72) (xy 204.47 45.72)
		)
		(stroke
			(width 0)
			(type default)
		)
	)
	(wire
		(pts
			(xy 171.45 45.72) (xy 172.72 45.72)
		)
		(stroke
			(width 0)
			(type default)
		)
	)
	(wire
		(pts
			(xy 262.89 167.64) (xy 262.89 168.91)
		)
		(stroke
			(width 0)
			(type default)
		)
	)
	(wire
		(pts
			(xy 261.62 245.11) (xy 265.43 245.11)
		)
		(stroke
			(width 0)
			(type default)
		)
	)
	(wire
		(pts
			(xy 33.02 168.91) (xy 35.56 168.91)
		)
		(stroke
			(width 0)
			(type default)
		)
	)
	(wire
		(pts
			(xy 303.53 132.08) (xy 314.96 132.08)
		)
		(stroke
			(width 0)
			(type default)
		)
	)
	(wire
		(pts
			(xy 317.5 96.52) (xy 317.5 111.76)
		)
		(stroke
			(width 0)
			(type default)
		)
	)
	(wire
		(pts
			(xy 88.9 73.66) (xy 102.87 73.66)
		)
		(stroke
			(width 0)
			(type default)
		)
	)
	(wire
		(pts
			(xy 265.43 274.32) (xy 267.97 274.32)
		)
		(stroke
			(width 0)
			(type default)
		)
	)
	(wire
		(pts
			(xy 331.47 38.1) (xy 334.01 38.1)
		)
		(stroke
			(width 0)
			(type default)
		)
	)
	(wire
		(pts
			(xy 224.79 181.61) (xy 199.39 181.61)
		)
		(stroke
			(width 0)
			(type default)
		)
	)
	(wire
		(pts
			(xy 271.78 86.36) (xy 279.4 86.36)
		)
		(stroke
			(width 0)
			(type default)
		)
	)
	(wire
		(pts
			(xy 331.47 76.2) (xy 359.41 76.2)
		)
		(stroke
			(width 0)
			(type default)
		)
	)
	(wire
		(pts
			(xy 312.42 179.07) (xy 328.93 179.07)
		)
		(stroke
			(width 0)
			(type default)
		)
	)
	(polyline
		(pts
			(xy 12.7 205.74) (xy 118.11 205.74)
		)
		(stroke
			(width 0)
			(type default)
		)
	)
	(wire
		(pts
			(xy 331.47 91.44) (xy 359.41 91.44)
		)
		(stroke
			(width 0)
			(type default)
		)
	)
	(wire
		(pts
			(xy 29.21 149.86) (xy 29.21 151.13)
		)
		(stroke
			(width 0)
			(type default)
		)
	)
	(wire
		(pts
			(xy 152.4 34.29) (xy 162.56 34.29)
		)
		(stroke
			(width 0)
			(type default)
		)
	)
	(wire
		(pts
			(xy 246.38 185.42) (xy 246.38 186.69)
		)
		(stroke
			(width 0)
			(type default)
		)
	)
	(wire
		(pts
			(xy 162.56 34.29) (xy 162.56 35.56)
		)
		(stroke
			(width 0)
			(type default)
		)
	)
	(wire
		(pts
			(xy 191.77 96.52) (xy 191.77 97.79)
		)
		(stroke
			(width 0)
			(type default)
		)
	)
	(polyline
		(pts
			(xy 231.14 118.11) (xy 199.39 118.11)
		)
		(stroke
			(width 0)
			(type default)
		)
	)
	(wire
		(pts
			(xy 57.15 149.86) (xy 62.23 149.86)
		)
		(stroke
			(width 0)
			(type default)
		)
	)
	(wire
		(pts
			(xy 162.56 40.64) (xy 162.56 50.8)
		)
		(stroke
			(width 0)
			(type default)
		)
	)
	(wire
		(pts
			(xy 317.5 129.54) (xy 317.5 137.16)
		)
		(stroke
			(width 0)
			(type default)
		)
	)
	(wire
		(pts
			(xy 265.43 273.05) (xy 265.43 274.32)
		)
		(stroke
			(width 0)
			(type default)
		)
	)
	(text "pinout compatible with \nwww.github.com/antmicro/ftdi-toolkit "
		(exclude_from_sim no)
		(at 33.655 221.615 0)
		(effects
			(font
				(size 2 2)
			)
			(justify left bottom)
		)
	)
	(text "Fan connector"
		(exclude_from_sim no)
		(at 27.94 127 0)
		(effects
			(font
				(size 4 4)
				(thickness 0.8)
				(bold yes)
			)
			(justify left bottom)
		)
	)
	(text "Expansion connector"
		(exclude_from_sim no)
		(at 292.735 21.59 0)
		(effects
			(font
				(size 4 4)
				(thickness 0.8)
				(bold yes)
			)
			(justify left bottom)
		)
	)
	(text "LED indicators"
		(exclude_from_sim no)
		(at 140.97 215.9 0)
		(effects
			(font
				(size 4 4)
				(thickness 0.8)
				(bold yes)
			)
			(justify left bottom)
		)
	)
	(text "Expansion connector resistors\n"
		(exclude_from_sim no)
		(at 113.03 127 0)
		(effects
			(font
				(size 4 4)
				(thickness 0.8)
				(bold yes)
			)
			(justify left bottom)
		)
	)
	(text "VCC depends on the power source\nPoE will supply 12 V\nUSB PD will supply 9 V or 15 V\nFor the Nano Fit DC IN we specify 9-20 V"
		(exclude_from_sim no)
		(at 244.475 160.655 0)
		(effects
			(font
				(size 1 1)
			)
			(justify left bottom)
		)
	)
	(text "GPIO expander"
		(exclude_from_sim no)
		(at 53.34 21.59 0)
		(effects
			(font
				(size 4 4)
				(thickness 0.8)
				(bold yes)
			)
			(justify left bottom)
		)
	)
	(text "Debug connector"
		(exclude_from_sim no)
		(at 33.02 213.36 0)
		(effects
			(font
				(size 4 4)
				(thickness 0.8)
				(bold yes)
			)
			(justify left bottom)
		)
	)
	(text "1V8 LOW POWER\nONLY FOR LEVEL\nSHIFTERS"
		(exclude_from_sim no)
		(at 290.195 161.29 0)
		(effects
			(font
				(size 1 1)
			)
			(justify left bottom)
		)
	)
	(text "Buttons"
		(exclude_from_sim no)
		(at 253.365 214.63 0)
		(effects
			(font
				(size 4 4)
				(thickness 0.8)
				(bold yes)
			)
			(justify left bottom)
		)
	)
	(text "I2C connector"
		(exclude_from_sim no)
		(at 163.83 21.59 0)
		(effects
			(font
				(size 4 4)
				(thickness 0.8)
				(bold yes)
			)
			(justify left bottom)
		)
	)
	(label "1V8_CONN"
		(at 307.34 179.07 180)
		(effects
			(font
				(size 1.27 1.27)
			)
			(justify right bottom)
		)
	)
	(label "GPIOEX_ADDR"
		(at 55.88 81.28 0)
		(effects
			(font
				(size 1.27 1.27)
			)
			(justify left bottom)
		)
	)
	(label "PCIE2_TX0_CONN_N"
		(at 292.1 45.72 0)
		(effects
			(font
				(size 1.27 1.27)
			)
			(justify left bottom)
		)
	)
	(label "GPIOEX_P0_4"
		(at 90.17 71.12 0)
		(effects
			(font
				(size 1.27 1.27)
			)
			(justify left bottom)
		)
	)
	(label "GPIO07_CONN"
		(at 154.94 138.43 180)
		(effects
			(font
				(size 1.27 1.27)
			)
			(justify right bottom)
		)
	)
	(label "GPIOEX_I2C_SCL"
		(at 68.58 73.66 180)
		(effects
			(font
				(size 1.27 1.27)
			)
			(justify right bottom)
		)
	)
	(label "GPIOEX_P0_5"
		(at 90.17 73.66 0)
		(effects
			(font
				(size 1.27 1.27)
			)
			(justify left bottom)
		)
	)
	(label "USB_CONN_N"
		(at 292.1 86.36 0)
		(effects
			(font
				(size 1.27 1.27)
			)
			(justify left bottom)
		)
	)
	(label "VCC_CONN"
		(at 257.81 179.07 180)
		(effects
			(font
				(size 1.27 1.27)
			)
			(justify right bottom)
		)
	)
	(label "MISO"
		(at 81.28 242.57 180)
		(effects
			(font
				(size 1.27 1.27)
			)
			(justify right bottom)
		)
	)
	(label "PCIE2_RST_CONN*"
		(at 154.94 146.05 180)
		(effects
			(font
				(size 1.27 1.27)
			)
			(justify right bottom)
		)
	)
	(label "PCIE2_TX0_CONN_N"
		(at 354.33 177.8 0)
		(effects
			(font
				(size 1.27 1.27)
			)
			(justify left bottom)
		)
	)
	(label "5V_CONN"
		(at 303.53 132.08 0)
		(effects
			(font
				(size 1.27 1.27)
			)
			(justify left bottom)
		)
	)
	(label "5V_CONN"
		(at 274.32 179.07 180)
		(effects
			(font
				(size 1.27 1.27)
			)
			(justify right bottom)
		)
	)
	(label "PCIE2_TX0_CONN_P"
		(at 292.1 48.26 0)
		(effects
			(font
				(size 1.27 1.27)
			)
			(justify left bottom)
		)
	)
	(label "I2S0_SCLK_CONN"
		(at 224.79 156.21 180)
		(effects
			(font
				(size 1.27 1.27)
			)
			(justify right bottom)
		)
	)
	(label "I2S0_SDOUT_CONN"
		(at 224.79 181.61 180)
		(effects
			(font
				(size 1.27 1.27)
			)
			(justify right bottom)
		)
	)
	(label "~{CS}"
		(at 39.37 234.95 0)
		(effects
			(font
				(size 1.27 1.27)
			)
			(justify left bottom)
		)
	)
	(label "I2C_CONN_PEN"
		(at 147.32 50.8 0)
		(effects
			(font
				(size 1.27 1.27)
			)
			(justify left bottom)
		)
	)
	(label "GPIO01_CONN"
		(at 292.1 73.66 0)
		(effects
			(font
				(size 1.27 1.27)
			)
			(justify left bottom)
		)
	)
	(label "PCIE_WAKE_SEL_EXT_CONN"
		(at 224.79 139.7 180)
		(effects
			(font
				(size 1.27 1.27)
			)
			(justify right bottom)
		)
	)
	(label "GPIO12_CONN"
		(at 224.79 163.83 180)
		(effects
			(font
				(size 1.27 1.27)
			)
			(justify right bottom)
		)
	)
	(label "SPI1_MOSI_CONN"
		(at 359.41 101.6 180)
		(effects
			(font
				(size 1.27 1.27)
			)
			(justify right bottom)
		)
	)
	(label "SPIO_MISO_CONN"
		(at 292.1 104.14 0)
		(effects
			(font
				(size 1.27 1.27)
			)
			(justify left bottom)
		)
	)
	(label "USBSS2_TX_CONN_N"
		(at 292.1 60.96 0)
		(effects
			(font
				(size 1.27 1.27)
			)
			(justify left bottom)
		)
	)
	(label "PCIE2_CLKREQ_CONN*"
		(at 292.1 71.12 0)
		(effects
			(font
				(size 1.27 1.27)
			)
			(justify left bottom)
		)
	)
	(label "VCC_CONN"
		(at 347.98 132.08 180)
		(effects
			(font
				(size 1.27 1.27)
			)
			(justify right bottom)
		)
	)
	(label "SPIO_SCK_CONN"
		(at 154.94 176.53 180)
		(effects
			(font
				(size 1.27 1.27)
			)
			(justify right bottom)
		)
	)
	(label "GPIO11_CONN"
		(at 224.79 161.29 180)
		(effects
			(font
				(size 1.27 1.27)
			)
			(justify right bottom)
		)
	)
	(label "PCIE3_CLKREQ_CONN*"
		(at 224.79 142.24 180)
		(effects
			(font
				(size 1.27 1.27)
			)
			(justify right bottom)
		)
	)
	(label "GPIO11_CONN"
		(at 359.41 86.36 180)
		(effects
			(font
				(size 1.27 1.27)
			)
			(justify right bottom)
		)
	)
	(label "SPIO_MOSI_CONN"
		(at 292.1 101.6 0)
		(effects
			(font
				(size 1.27 1.27)
			)
			(justify left bottom)
		)
	)
	(label "1V8_CONN"
		(at 303.53 127 0)
		(effects
			(font
				(size 1.27 1.27)
			)
			(justify left bottom)
		)
	)
	(label "FAN_TACH_5V"
		(at 57.15 168.91 0)
		(effects
			(font
				(size 1.27 1.27)
			)
			(justify left bottom)
		)
	)
	(label "GPIO07_CONN"
		(at 292.1 76.2 0)
		(effects
			(font
				(size 1.27 1.27)
			)
			(justify left bottom)
		)
	)
	(label "GPIO09_CONN"
		(at 292.1 78.74 0)
		(effects
			(font
				(size 1.27 1.27)
			)
			(justify left bottom)
		)
	)
	(label "SCK"
		(at 82.55 237.49 0)
		(effects
			(font
				(size 1.27 1.27)
			)
			(justify left bottom)
		)
	)
	(label "PCIE2_TX0_CONN_P"
		(at 354.33 182.88 0)
		(effects
			(font
				(size 1.27 1.27)
			)
			(justify left bottom)
		)
	)
	(label "USBSS2_TX_CONN_P"
		(at 353.06 243.84 0)
		(effects
			(font
				(size 1.27 1.27)
			)
			(justify left bottom)
		)
	)
	(label "I2S0_LRCK_CONN"
		(at 292.1 93.98 0)
		(effects
			(font
				(size 1.27 1.27)
			)
			(justify left bottom)
		)
	)
	(label "GPIO09_CONN"
		(at 154.94 158.75 180)
		(effects
			(font
				(size 1.27 1.27)
			)
			(justify right bottom)
		)
	)
	(label "MISO"
		(at 53.34 260.35 0)
		(effects
			(font
				(size 1.27 1.27)
			)
			(justify left bottom)
		)
	)
	(label "~{SPI1_CS0_CONN}"
		(at 359.41 106.68 180)
		(effects
			(font
				(size 1.27 1.27)
			)
			(justify right bottom)
		)
	)
	(label "SPIO_MISO_CONN"
		(at 154.94 196.85 180)
		(effects
			(font
				(size 1.27 1.27)
			)
			(justify right bottom)
		)
	)
	(label "MOSI"
		(at 82.55 234.95 0)
		(effects
			(font
				(size 1.27 1.27)
			)
			(justify left bottom)
		)
	)
	(label "GPIOEX_P0_3"
		(at 90.17 68.58 0)
		(effects
			(font
				(size 1.27 1.27)
			)
			(justify left bottom)
		)
	)
	(label "GPIOEX_P0_1"
		(at 90.17 63.5 0)
		(effects
			(font
				(size 1.27 1.27)
			)
			(justify left bottom)
		)
	)
	(label "USB_CONN_P"
		(at 292.1 88.9 0)
		(effects
			(font
				(size 1.27 1.27)
			)
			(justify left bottom)
		)
	)
	(label "SCK"
		(at 39.37 240.03 0)
		(effects
			(font
				(size 1.27 1.27)
			)
			(justify left bottom)
		)
	)
	(label "~{CS}"
		(at 82.55 232.41 0)
		(effects
			(font
				(size 1.27 1.27)
			)
			(justify left bottom)
		)
	)
	(label "MISO"
		(at 82.55 240.03 0)
		(effects
			(font
				(size 1.27 1.27)
			)
			(justify left bottom)
		)
	)
	(label "3V3_CONN"
		(at 303.53 121.92 0)
		(effects
			(font
				(size 1.27 1.27)
			)
			(justify left bottom)
		)
	)
	(label "~{SPI0_CS0_CONN}"
		(at 292.1 106.68 0)
		(effects
			(font
				(size 1.27 1.27)
			)
			(justify left bottom)
		)
	)
	(label "PCIE3_CLKREQ_CONN*"
		(at 359.41 73.66 180)
		(effects
			(font
				(size 1.27 1.27)
			)
			(justify right bottom)
		)
	)
	(label "SPIO_MOSI_CONN"
		(at 154.94 173.99 180)
		(effects
			(font
				(size 1.27 1.27)
			)
			(justify right bottom)
		)
	)
	(label "PCIE2_TX1_CONN_N"
		(at 292.1 38.1 0)
		(effects
			(font
				(size 1.27 1.27)
			)
			(justify left bottom)
		)
	)
	(label "SPI1_MOSI_CONN"
		(at 224.79 176.53 180)
		(effects
			(font
				(size 1.27 1.27)
			)
			(justify right bottom)
		)
	)
	(label "UART1_RXD_CONN"
		(at 154.94 156.21 180)
		(effects
			(font
				(size 1.27 1.27)
			)
			(justify right bottom)
		)
	)
	(label "SPIO_SCK_CONN"
		(at 292.1 99.06 0)
		(effects
			(font
				(size 1.27 1.27)
			)
			(justify left bottom)
		)
	)
	(label "GPIO13_CONN"
		(at 359.41 78.74 180)
		(effects
			(font
				(size 1.27 1.27)
			)
			(justify right bottom)
		)
	)
	(label "GPIOEX_P0_6"
		(at 90.17 76.2 0)
		(effects
			(font
				(size 1.27 1.27)
			)
			(justify left bottom)
		)
	)
	(label "PCIE_WAKE_SEL_EXT_CONN"
		(at 359.41 76.2 180)
		(effects
			(font
				(size 1.27 1.27)
			)
			(justify right bottom)
		)
	)
	(label "GPIO12_CONN"
		(at 359.41 83.82 180)
		(effects
			(font
				(size 1.27 1.27)
			)
			(justify right bottom)
		)
	)
	(label "UART1_TXD_CONN"
		(at 224.79 158.75 180)
		(effects
			(font
				(size 1.27 1.27)
			)
			(justify right bottom)
		)
	)
	(label "I2S0_SDOUT_CONN"
		(at 359.41 93.98 180)
		(effects
			(font
				(size 1.27 1.27)
			)
			(justify right bottom)
		)
	)
	(label "~{SPI0_CS1_CONN}"
		(at 154.94 191.77 180)
		(effects
			(font
				(size 1.27 1.27)
			)
			(justify right bottom)
		)
	)
	(label "UART1_RXD_CONN"
		(at 292.1 83.82 0)
		(effects
			(font
				(size 1.27 1.27)
			)
			(justify left bottom)
		)
	)
	(label "GPIOEX_P0_0"
		(at 90.17 60.96 0)
		(effects
			(font
				(size 1.27 1.27)
			)
			(justify left bottom)
		)
	)
	(label "GPIOEX_P0_2"
		(at 90.17 66.04 0)
		(effects
			(font
				(size 1.27 1.27)
			)
			(justify left bottom)
		)
	)
	(label "MOSI"
		(at 53.34 262.89 0)
		(effects
			(font
				(size 1.27 1.27)
			)
			(justify left bottom)
		)
	)
	(label "GPIOEX_P0_7"
		(at 90.17 78.74 0)
		(effects
			(font
				(size 1.27 1.27)
			)
			(justify left bottom)
		)
	)
	(label "PCIE2_TX1_CONN_P"
		(at 292.1 40.64 0)
		(effects
			(font
				(size 1.27 1.27)
			)
			(justify left bottom)
		)
	)
	(label "GPIO13_CONN"
		(at 224.79 137.16 180)
		(effects
			(font
				(size 1.27 1.27)
			)
			(justify right bottom)
		)
	)
	(label "UART1_TXD_CONN"
		(at 359.41 88.9 180)
		(effects
			(font
				(size 1.27 1.27)
			)
			(justify right bottom)
		)
	)
	(label "~{SPI0_CS0_CONN}"
		(at 154.94 194.31 180)
		(effects
			(font
				(size 1.27 1.27)
			)
			(justify right bottom)
		)
	)
	(label "~{SPI1_CS1_CONN}"
		(at 224.79 191.77 180)
		(effects
			(font
				(size 1.27 1.27)
			)
			(justify right bottom)
		)
	)
	(label "SCK"
		(at 53.34 257.81 0)
		(effects
			(font
				(size 1.27 1.27)
			)
			(justify left bottom)
		)
	)
	(label "FAN_PWM_5V"
		(at 57.15 166.37 0)
		(effects
			(font
				(size 1.27 1.27)
			)
			(justify left bottom)
		)
	)
	(label "PCIE2_CLKREQ_CONN*"
		(at 154.94 143.51 180)
		(effects
			(font
				(size 1.27 1.27)
			)
			(justify right bottom)
		)
	)
	(label "PCIE3_RST_CONN*"
		(at 359.41 71.12 180)
		(effects
			(font
				(size 1.27 1.27)
			)
			(justify right bottom)
		)
	)
	(label "PCIE2_TX1_CONN_P"
		(at 354.33 213.36 0)
		(effects
			(font
				(size 1.27 1.27)
			)
			(justify left bottom)
		)
	)
	(label "~{SPI1_CS0_CONN}"
		(at 224.79 194.31 180)
		(effects
			(font
				(size 1.27 1.27)
			)
			(justify right bottom)
		)
	)
	(label "SPI1_SCK_CONN"
		(at 359.41 99.06 180)
		(effects
			(font
				(size 1.27 1.27)
			)
			(justify right bottom)
		)
	)
	(label "GPIOEX_RESET"
		(at 68.58 77.47 180)
		(effects
			(font
				(size 1.27 1.27)
			)
			(justify right bottom)
		)
	)
	(label "GPIOEX_I2C_SDA"
		(at 68.58 71.12 180)
		(effects
			(font
				(size 1.27 1.27)
			)
			(justify right bottom)
		)
	)
	(label "SPI1_MISO_CONN"
		(at 224.79 173.99 180)
		(effects
			(font
				(size 1.27 1.27)
			)
			(justify right bottom)
		)
	)
	(label "PCIE2_TX1_CONN_N"
		(at 354.33 208.28 0)
		(effects
			(font
				(size 1.27 1.27)
			)
			(justify left bottom)
		)
	)
	(label "3V3_STDB_CONN"
		(at 353.06 127 180)
		(effects
			(font
				(size 1.27 1.27)
			)
			(justify right bottom)
		)
	)
	(label "I2S0_SCLK_CONN"
		(at 359.41 91.44 180)
		(effects
			(font
				(size 1.27 1.27)
			)
			(justify right bottom)
		)
	)
	(label "I2S0_LRCK_CONN"
		(at 154.94 179.07 180)
		(effects
			(font
				(size 1.27 1.27)
			)
			(justify right bottom)
		)
	)
	(label "I2S0_SDIN_CONN"
		(at 292.1 91.44 0)
		(effects
			(font
				(size 1.27 1.27)
			)
			(justify left bottom)
		)
	)
	(label "PCIE2_RST_CONN*"
		(at 292.1 68.58 0)
		(effects
			(font
				(size 1.27 1.27)
			)
			(justify left bottom)
		)
	)
	(label "USBSS2_TX_CONN_P"
		(at 292.1 63.5 0)
		(effects
			(font
				(size 1.27 1.27)
			)
			(justify left bottom)
		)
	)
	(label "MOSI"
		(at 81.28 237.49 180)
		(effects
			(font
				(size 1.27 1.27)
			)
			(justify right bottom)
		)
	)
	(label "SPI1_SCK_CONN"
		(at 224.79 179.07 180)
		(effects
			(font
				(size 1.27 1.27)
			)
			(justify right bottom)
		)
	)
	(label "~{SPI1_CS1_CONN}"
		(at 359.41 109.22 180)
		(effects
			(font
				(size 1.27 1.27)
			)
			(justify right bottom)
		)
	)
	(label "PCIE3_RST_CONN*"
		(at 224.79 144.78 180)
		(effects
			(font
				(size 1.27 1.27)
			)
			(justify right bottom)
		)
	)
	(label "USBSS2_TX_CONN_N"
		(at 353.06 238.76 0)
		(effects
			(font
				(size 1.27 1.27)
			)
			(justify left bottom)
		)
	)
	(label "3V3_CONN"
		(at 290.83 179.07 180)
		(effects
			(font
				(size 1.27 1.27)
			)
			(justify right bottom)
		)
	)
	(label "I2S0_SDIN_CONN"
		(at 154.94 181.61 180)
		(effects
			(font
				(size 1.27 1.27)
			)
			(justify right bottom)
		)
	)
	(label "3V3_STDB_CONN"
		(at 328.93 179.07 180)
		(effects
			(font
				(size 1.27 1.27)
			)
			(justify right bottom)
		)
	)
	(label "SPI1_MISO_CONN"
		(at 359.41 104.14 180)
		(effects
			(font
				(size 1.27 1.27)
			)
			(justify right bottom)
		)
	)
	(label "~{SPI0_CS1_CONN}"
		(at 292.1 109.22 0)
		(effects
			(font
				(size 1.27 1.27)
			)
			(justify left bottom)
		)
	)
	(label "GPIO01_CONN"
		(at 154.94 140.97 180)
		(effects
			(font
				(size 1.27 1.27)
			)
			(justify right bottom)
		)
	)
	(label "I2C_CONN_3V3"
		(at 189.23 45.72 0)
		(effects
			(font
				(size 1.27 1.27)
			)
			(justify left bottom)
		)
	)
	(global_label "SPI1_MOSI"
		(shape input)
		(at 177.8 176.53 180)
		(fields_autoplaced yes)
		(effects
			(font
				(size 1.27 1.27)
			)
			(justify right)
		)
		(property "Intersheetrefs" "${INTERSHEET_REFS}"
			(at 165.5293 176.4506 0)
			(effects
				(font
					(size 1.27 1.27)
				)
				(justify right)
			)
		)
	)
	(global_label "I2C1_SDA"
		(shape bidirectional)
		(at 173.99 86.36 180)
		(effects
			(font
				(size 1.27 1.27)
			)
			(justify right)
		)
		(property "Intersheetrefs" "${INTERSHEET_REFS}"
			(at 161.29 86.36 0)
			(effects
				(font
					(size 1.27 1.27)
				)
				(justify right)
			)
		)
	)
	(global_label "GPIO12"
		(shape input)
		(at 173.99 163.83 180)
		(fields_autoplaced yes)
		(effects
			(font
				(size 1.27 1.27)
			)
			(justify right)
		)
		(property "Intersheetrefs" "${INTERSHEET_REFS}"
			(at 164.6826 163.7506 0)
			(effects
				(font
					(size 1.27 1.27)
				)
				(justify right)
			)
		)
	)
	(global_label "USB1_D_N"
		(shape input)
		(at 372.11 157.48 180)
		(effects
			(font
				(size 1.27 1.27)
			)
			(justify right)
		)
		(property "Intersheetrefs" "${INTERSHEET_REFS}"
			(at 356.235 157.48 0)
			(effects
				(font
					(size 1.27 1.27)
				)
				(justify right)
			)
		)
	)
	(global_label "PCIE3_CLK_N"
		(shape bidirectional)
		(at 342.9 55.88 0)
		(effects
			(font
				(size 1.27 1.27)
			)
			(justify left)
		)
		(property "Intersheetrefs" "${INTERSHEET_REFS}"
			(at 361.315 55.88 0)
			(effects
				(font
					(size 1.27 1.27)
				)
				(justify left)
			)
		)
	)
	(global_label "USBC1_FLG"
		(shape input)
		(at 115.57 76.2 0)
		(effects
			(font
				(size 1.27 1.27)
			)
			(justify left)
		)
		(property "Intersheetrefs" "${INTERSHEET_REFS}"
			(at 129.54 76.2 0)
			(effects
				(font
					(size 1.27 1.27)
				)
				(justify left)
			)
		)
	)
	(global_label "PDC_MOSI"
		(shape output)
		(at 99.06 234.95 0)
		(fields_autoplaced yes)
		(effects
			(font
				(size 1.27 1.27)
			)
			(justify left)
		)
		(property "Intersheetrefs" "${INTERSHEET_REFS}"
			(at 111.419 234.95 0)
			(effects
				(font
					(size 1.27 1.27)
				)
				(justify left)
			)
		)
	)
	(global_label "SPIO_MISO"
		(shape input)
		(at 110.49 196.85 180)
		(fields_autoplaced yes)
		(effects
			(font
				(size 1.27 1.27)
			)
			(justify right)
		)
		(property "Intersheetrefs" "${INTERSHEET_REFS}"
			(at 98.0983 196.7706 0)
			(effects
				(font
					(size 1.27 1.27)
				)
				(justify right)
			)
		)
	)
	(global_label "I2C1_SCL"
		(shape output)
		(at 173.99 88.9 180)
		(effects
			(font
				(size 1.27 1.27)
			)
			(justify right)
		)
		(property "Intersheetrefs" "${INTERSHEET_REFS}"
			(at 161.29 88.9 0)
			(effects
				(font
					(size 1.27 1.27)
				)
				(justify right)
			)
		)
	)
	(global_label "FAN_TACH"
		(shape output)
		(at 33.02 168.91 180)
		(fields_autoplaced yes)
		(effects
			(font
				(size 1.27 1.27)
			)
			(justify right)
		)
		(property "Intersheetrefs" "${INTERSHEET_REFS}"
			(at 21.475 168.8306 0)
			(effects
				(font
					(size 1.27 1.27)
				)
				(justify right)
			)
		)
	)
	(global_label "USB1_D_P"
		(shape input)
		(at 271.78 88.9 180)
		(effects
			(font
				(size 1.27 1.27)
			)
			(justify right)
		)
		(property "Intersheetrefs" "${INTERSHEET_REFS}"
			(at 255.905 88.9 0)
			(effects
				(font
					(size 1.27 1.27)
				)
				(justify right)
			)
		)
	)
	(global_label "SYS_SCL"
		(shape input)
		(at 38.1 73.66 180)
		(fields_autoplaced yes)
		(effects
			(font
				(size 1.27 1.27)
			)
			(justify right)
		)
		(property "Intersheetrefs" "${INTERSHEET_REFS}"
			(at 27.132 73.66 0)
			(effects
				(font
					(size 1.27 1.27)
				)
				(justify right)
			)
		)
	)
	(global_label "USB1_D_N"
		(shape input)
		(at 271.78 86.36 180)
		(effects
			(font
				(size 1.27 1.27)
			)
			(justify right)
		)
		(property "Intersheetrefs" "${INTERSHEET_REFS}"
			(at 255.905 86.36 0)
			(effects
				(font
					(size 1.27 1.27)
				)
				(justify right)
			)
		)
	)
	(global_label "~{PDC_CS}"
		(shape output)
		(at 99.06 232.41 0)
		(fields_autoplaced yes)
		(effects
			(font
				(size 1.27 1.27)
			)
			(justify left)
		)
		(property "Intersheetrefs" "${INTERSHEET_REFS}"
			(at 109.3023 232.41 0)
			(effects
				(font
					(size 1.27 1.27)
				)
				(justify left)
			)
		)
	)
	(global_label "USBSS1_RX_P"
		(shape output)
		(at 342.9 66.04 0)
		(effects
			(font
				(size 1.27 1.27)
			)
			(justify left)
		)
		(property "Intersheetrefs" "${INTERSHEET_REFS}"
			(at 359.41 66.04 0)
			(effects
				(font
					(size 1.1 1.1)
				)
				(justify left)
			)
		)
	)
	(global_label "PCIE2_CLK_P"
		(shape bidirectional)
		(at 372.11 193.04 180)
		(effects
			(font
				(size 1.27 1.27)
			)
			(justify right)
		)
		(property "Intersheetrefs" "${INTERSHEET_REFS}"
			(at 355.6 193.04 0)
			(effects
				(font
					(size 1.27 1.27)
				)
				(justify right)
			)
		)
	)
	(global_label "USB1_D_P"
		(shape input)
		(at 372.11 162.56 180)
		(effects
			(font
				(size 1.27 1.27)
			)
			(justify right)
		)
		(property "Intersheetrefs" "${INTERSHEET_REFS}"
			(at 356.235 162.56 0)
			(effects
				(font
					(size 1.27 1.27)
				)
				(justify right)
			)
		)
	)
	(global_label "~{SPI1_CS0}"
		(shape input)
		(at 175.26 194.31 180)
		(fields_autoplaced yes)
		(effects
			(font
				(size 1.27 1.27)
			)
			(justify right)
		)
		(property "Intersheetrefs" "${INTERSHEET_REFS}"
			(at 163.8964 194.3894 0)
			(effects
				(font
					(size 1.27 1.27)
				)
				(justify right)
			)
		)
	)
	(global_label "CSIB_PEN"
		(shape output)
		(at 115.57 63.5 0)
		(effects
			(font
				(size 1.27 1.27)
			)
			(justify left)
		)
		(property "Intersheetrefs" "${INTERSHEET_REFS}"
			(at 129.54 63.5 0)
			(effects
				(font
					(size 1.27 1.27)
				)
				(justify left)
			)
		)
	)
	(global_label "SYS_SDA"
		(shape bidirectional)
		(at 328.93 234.95 180)
		(effects
			(font
				(size 1.27 1.27)
			)
			(justify right)
		)
		(property "Intersheetrefs" "${INTERSHEET_REFS}"
			(at 316.23 234.95 0)
			(effects
				(font
					(size 1.27 1.27)
				)
				(justify right)
			)
		)
	)
	(global_label "SPIO_MOSI"
		(shape input)
		(at 111.76 173.99 180)
		(fields_autoplaced yes)
		(effects
			(font
				(size 1.27 1.27)
			)
			(justify right)
		)
		(property "Intersheetrefs" "${INTERSHEET_REFS}"
			(at 99.3683 173.9106 0)
			(effects
				(font
					(size 1.27 1.27)
				)
				(justify right)
			)
		)
	)
	(global_label "CSIB_FLG"
		(shape input)
		(at 115.57 73.66 0)
		(effects
			(font
				(size 1.27 1.27)
			)
			(justify left)
		)
		(property "Intersheetrefs" "${INTERSHEET_REFS}"
			(at 129.54 73.66 0)
			(effects
				(font
					(size 1.27 1.27)
				)
				(justify left)
			)
		)
	)
	(global_label "GPIO09"
		(shape input)
		(at 109.22 158.75 180)
		(fields_autoplaced yes)
		(effects
			(font
				(size 1.27 1.27)
			)
			(justify right)
		)
		(property "Intersheetrefs" "${INTERSHEET_REFS}"
			(at 99.9126 158.8294 0)
			(effects
				(font
					(size 1.27 1.27)
				)
				(justify right)
			)
		)
	)
	(global_label "PCIE2_RX0_N"
		(shape bidirectional)
		(at 372.11 167.64 180)
		(effects
			(font
				(size 1.27 1.27)
			)
			(justify right)
		)
		(property "Intersheetrefs" "${INTERSHEET_REFS}"
			(at 355.6 167.64 0)
			(effects
				(font
					(size 1.27 1.27)
				)
				(justify right)
			)
		)
	)
	(global_label "CAN_RX"
		(shape input)
		(at 359.41 119.38 0)
		(effects
			(font
				(size 1.27 1.27)
			)
			(justify left)
		)
		(property "Intersheetrefs" "${INTERSHEET_REFS}"
			(at 373.38 119.38 0)
			(effects
				(font
					(size 1.27 1.27)
				)
				(justify left)
			)
		)
	)
	(global_label "USBC1_PEN"
		(shape output)
		(at 115.57 66.04 0)
		(effects
			(font
				(size 1.27 1.27)
			)
			(justify left)
		)
		(property "Intersheetrefs" "${INTERSHEET_REFS}"
			(at 129.54 66.04 0)
			(effects
				(font
					(size 1.27 1.27)
				)
				(justify left)
			)
		)
	)
	(global_label "I2S0_SDIN"
		(shape input)
		(at 111.76 181.61 180)
		(fields_autoplaced yes)
		(effects
			(font
				(size 1.27 1.27)
			)
			(justify right)
		)
		(property "Intersheetrefs" "${INTERSHEET_REFS}"
			(at 99.7312 181.5306 0)
			(effects
				(font
					(size 1.27 1.27)
				)
				(justify right)
			)
		)
	)
	(global_label "CSIA_PEN"
		(shape output)
		(at 115.57 60.96 0)
		(effects
			(font
				(size 1.27 1.27)
			)
			(justify left)
		)
		(property "Intersheetrefs" "${INTERSHEET_REFS}"
			(at 129.54 60.96 0)
			(effects
				(font
					(size 1.27 1.27)
				)
				(justify left)
			)
		)
	)
	(global_label "PCIE3_CLKREQ*"
		(shape input)
		(at 181.61 142.24 180)
		(fields_autoplaced yes)
		(effects
			(font
				(size 1.27 1.27)
			)
			(justify right)
		)
		(property "Intersheetrefs" "${INTERSHEET_REFS}"
			(at 164.4407 142.1606 0)
			(effects
				(font
					(size 1.27 1.27)
				)
				(justify right)
			)
		)
	)
	(global_label "USER_BTN0"
		(shape output)
		(at 270.51 232.41 0)
		(fields_autoplaced yes)
		(effects
			(font
				(size 1.27 1.27)
			)
			(justify left)
		)
		(property "Intersheetrefs" "${INTERSHEET_REFS}"
			(at 284.1994 232.41 0)
			(effects
				(font
					(size 1.27 1.27)
				)
				(justify left)
			)
		)
	)
	(global_label "GPIO13"
		(shape input)
		(at 181.61 137.16 180)
		(fields_autoplaced yes)
		(effects
			(font
				(size 1.27 1.27)
			)
			(justify right)
		)
		(property "Intersheetrefs" "${INTERSHEET_REFS}"
			(at 172.3026 137.0806 0)
			(effects
				(font
					(size 1.27 1.27)
				)
				(justify right)
			)
		)
	)
	(global_label "SYS_SCL"
		(shape bidirectional)
		(at 93.98 257.81 0)
		(fields_autoplaced yes)
		(effects
			(font
				(size 1.27 1.27)
			)
			(justify left)
		)
		(property "Intersheetrefs" "${INTERSHEET_REFS}"
			(at 106.0593 257.81 0)
			(effects
				(font
					(size 1.27 1.27)
				)
				(justify left)
			)
		)
	)
	(global_label "PCIE3_RST*"
		(shape input)
		(at 181.61 144.78 180)
		(fields_autoplaced yes)
		(effects
			(font
				(size 1.27 1.27)
			)
			(justify right)
		)
		(property "Intersheetrefs" "${INTERSHEET_REFS}"
			(at 168.3112 144.7006 0)
			(effects
				(font
					(size 1.27 1.27)
				)
				(justify right)
			)
		)
	)
	(global_label "SYS_SCL"
		(shape input)
		(at 328.93 237.49 180)
		(effects
			(font
				(size 1.27 1.27)
			)
			(justify right)
		)
		(property "Intersheetrefs" "${INTERSHEET_REFS}"
			(at 316.23 237.49 0)
			(effects
				(font
					(size 1.27 1.27)
				)
				(justify right)
			)
		)
	)
	(global_label "I2C2_SDA"
		(shape bidirectional)
		(at 359.41 114.3 0)
		(effects
			(font
				(size 1.27 1.27)
			)
			(justify left)
		)
		(property "Intersheetrefs" "${INTERSHEET_REFS}"
			(at 373.38 114.3 0)
			(effects
				(font
					(size 1.27 1.27)
				)
				(justify left)
			)
		)
	)
	(global_label "PDC_SCLK"
		(shape output)
		(at 99.06 237.49 0)
		(fields_autoplaced yes)
		(effects
			(font
				(size 1.27 1.27)
			)
			(justify left)
		)
		(property "Intersheetrefs" "${INTERSHEET_REFS}"
			(at 111.6004 237.49 0)
			(effects
				(font
					(size 1.27 1.27)
				)
				(justify left)
			)
		)
	)
	(global_label "DISABLE_POE_DCDC"
		(shape output)
		(at 115.57 68.58 0)
		(effects
			(font
				(size 1.27 1.27)
			)
			(justify left)
		)
		(property "Intersheetrefs" "${INTERSHEET_REFS}"
			(at 137.16 68.58 0)
			(effects
				(font
					(size 1.27 1.27)
				)
				(justify left)
			)
		)
	)
	(global_label "USBSS1_TX_P"
		(shape input)
		(at 271.78 63.5 180)
		(effects
			(font
				(size 1.27 1.27)
			)
			(justify right)
		)
		(property "Intersheetrefs" "${INTERSHEET_REFS}"
			(at 255.27 63.5 0)
			(effects
				(font
					(size 1.1 1.1)
				)
				(justify right)
			)
		)
	)
	(global_label "~{GPIO_INT}"
		(shape output)
		(at 38.1 67.31 180)
		(fields_autoplaced yes)
		(effects
			(font
				(size 1.27 1.27)
			)
			(justify right)
		)
		(property "Intersheetrefs" "${INTERSHEET_REFS}"
			(at 26.769 67.31 0)
			(effects
				(font
					(size 1.27 1.27)
				)
				(justify right)
			)
		)
	)
	(global_label "USBSS1_RX_P"
		(shape output)
		(at 372.11 233.68 180)
		(effects
			(font
				(size 1.27 1.27)
			)
			(justify right)
		)
		(property "Intersheetrefs" "${INTERSHEET_REFS}"
			(at 355.6 233.68 0)
			(effects
				(font
					(size 1.1 1.1)
				)
				(justify right)
			)
		)
	)
	(global_label "USBSS1_RX_N"
		(shape output)
		(at 372.11 228.6 180)
		(effects
			(font
				(size 1.27 1.27)
			)
			(justify right)
		)
		(property "Intersheetrefs" "${INTERSHEET_REFS}"
			(at 355.6 228.6 0)
			(effects
				(font
					(size 1.1 1.1)
				)
				(justify right)
			)
		)
	)
	(global_label "PCIE2_TX0_N"
		(shape input)
		(at 271.78 45.72 180)
		(effects
			(font
				(size 1.27 1.27)
			)
			(justify right)
		)
		(property "Intersheetrefs" "${INTERSHEET_REFS}"
			(at 253.365 45.72 0)
			(effects
				(font
					(size 1.27 1.27)
				)
				(justify right)
			)
		)
	)
	(global_label "FAN_PWM"
		(shape input)
		(at 33.02 166.37 180)
		(fields_autoplaced yes)
		(effects
			(font
				(size 1.27 1.27)
			)
			(justify right)
		)
		(property "Intersheetrefs" "${INTERSHEET_REFS}"
			(at 21.9588 166.2906 0)
			(effects
				(font
					(size 1.27 1.27)
				)
				(justify right)
			)
		)
	)
	(global_label "I2S0_SCLK"
		(shape input)
		(at 173.99 156.21 180)
		(fields_autoplaced yes)
		(effects
			(font
				(size 1.27 1.27)
			)
			(justify right)
		)
		(property "Intersheetrefs" "${INTERSHEET_REFS}"
			(at 161.5983 156.1306 0)
			(effects
				(font
					(size 1.27 1.27)
				)
				(justify right)
			)
		)
	)
	(global_label "PCIE2_RX1_P"
		(shape bidirectional)
		(at 372.11 203.2 180)
		(effects
			(font
				(size 1.27 1.27)
			)
			(justify right)
		)
		(property "Intersheetrefs" "${INTERSHEET_REFS}"
			(at 355.6 203.2 0)
			(effects
				(font
					(size 1.27 1.27)
				)
				(justify right)
			)
		)
	)
	(global_label "PCIE2_RX1_N"
		(shape output)
		(at 342.9 40.64 0)
		(effects
			(font
				(size 1.27 1.27)
			)
			(justify left)
		)
		(property "Intersheetrefs" "${INTERSHEET_REFS}"
			(at 361.315 40.64 0)
			(effects
				(font
					(size 1.27 1.27)
				)
				(justify left)
			)
		)
	)
	(global_label "SPI1_MISO"
		(shape input)
		(at 177.8 173.99 180)
		(fields_autoplaced yes)
		(effects
			(font
				(size 1.27 1.27)
			)
			(justify right)
		)
		(property "Intersheetrefs" "${INTERSHEET_REFS}"
			(at 165.5293 173.9106 0)
			(effects
				(font
					(size 1.27 1.27)
				)
				(justify right)
			)
		)
	)
	(global_label "USER_BTN1"
		(shape output)
		(at 270.51 261.62 0)
		(fields_autoplaced yes)
		(effects
			(font
				(size 1.27 1.27)
			)
			(justify left)
		)
		(property "Intersheetrefs" "${INTERSHEET_REFS}"
			(at 284.1994 261.62 0)
			(effects
				(font
					(size 1.27 1.27)
				)
				(justify left)
			)
		)
	)
	(global_label "SPI1_SCK"
		(shape input)
		(at 177.8 179.07 180)
		(fields_autoplaced yes)
		(effects
			(font
				(size 1.27 1.27)
			)
			(justify right)
		)
		(property "Intersheetrefs" "${INTERSHEET_REFS}"
			(at 166.3759 178.9906 0)
			(effects
				(font
					(size 1.27 1.27)
				)
				(justify right)
			)
		)
	)
	(global_label "SPIO_SCK"
		(shape input)
		(at 111.76 176.53 180)
		(fields_autoplaced yes)
		(effects
			(font
				(size 1.27 1.27)
			)
			(justify right)
		)
		(property "Intersheetrefs" "${INTERSHEET_REFS}"
			(at 100.215 176.4506 0)
			(effects
				(font
					(size 1.27 1.27)
				)
				(justify right)
			)
		)
	)
	(global_label "PCIE2_CLK_P"
		(shape input)
		(at 271.78 55.88 180)
		(effects
			(font
				(size 1.27 1.27)
			)
			(justify right)
		)
		(property "Intersheetrefs" "${INTERSHEET_REFS}"
			(at 253.365 55.88 0)
			(effects
				(font
					(size 1.27 1.27)
				)
				(justify right)
			)
		)
	)
	(global_label "PCIE2_TX1_P"
		(shape input)
		(at 271.78 40.64 180)
		(effects
			(font
				(size 1.27 1.27)
			)
			(justify right)
		)
		(property "Intersheetrefs" "${INTERSHEET_REFS}"
			(at 253.365 40.64 0)
			(effects
				(font
					(size 1.27 1.27)
				)
				(justify right)
			)
		)
	)
	(global_label "USER_LED0"
		(shape input)
		(at 138.43 251.46 180)
		(effects
			(font
				(size 1.27 1.27)
			)
			(justify right)
		)
		(property "Intersheetrefs" "${INTERSHEET_REFS}"
			(at 125.095 251.46 0)
			(effects
				(font
					(size 1.27 1.27)
				)
				(justify right)
			)
		)
	)
	(global_label "PCIE3_CLK_P"
		(shape bidirectional)
		(at 372.11 223.52 180)
		(effects
			(font
				(size 1.27 1.27)
			)
			(justify right)
		)
		(property "Intersheetrefs" "${INTERSHEET_REFS}"
			(at 355.6 223.52 0)
			(effects
				(font
					(size 1.27 1.27)
				)
				(justify right)
			)
		)
	)
	(global_label "PCIE2_RX0_P"
		(shape bidirectional)
		(at 372.11 172.72 180)
		(effects
			(font
				(size 1.27 1.27)
			)
			(justify right)
		)
		(property "Intersheetrefs" "${INTERSHEET_REFS}"
			(at 355.6 172.72 0)
			(effects
				(font
					(size 1.27 1.27)
				)
				(justify right)
			)
		)
	)
	(global_label "UART1_TXD"
		(shape input)
		(at 173.99 158.75 180)
		(fields_autoplaced yes)
		(effects
			(font
				(size 1.27 1.27)
			)
			(justify right)
		)
		(property "Intersheetrefs" "${INTERSHEET_REFS}"
			(at 161.2959 158.8294 0)
			(effects
				(font
					(size 1.27 1.27)
				)
				(justify right)
			)
		)
	)
	(global_label "I2S0_SDOUT"
		(shape input)
		(at 177.8 181.61 180)
		(fields_autoplaced yes)
		(effects
			(font
				(size 1.27 1.27)
			)
			(justify right)
		)
		(property "Intersheetrefs" "${INTERSHEET_REFS}"
			(at 164.0779 181.5306 0)
			(effects
				(font
					(size 1.27 1.27)
				)
				(justify right)
			)
		)
	)
	(global_label "I2S0_LRCK"
		(shape input)
		(at 111.76 179.07 180)
		(fields_autoplaced yes)
		(effects
			(font
				(size 1.27 1.27)
			)
			(justify right)
		)
		(property "Intersheetrefs" "${INTERSHEET_REFS}"
			(at 99.3079 178.9906 0)
			(effects
				(font
					(size 1.27 1.27)
				)
				(justify right)
			)
		)
	)
	(global_label "UART1_RXD"
		(shape input)
		(at 109.22 156.21 180)
		(fields_autoplaced yes)
		(effects
			(font
				(size 1.27 1.27)
			)
			(justify right)
		)
		(property "Intersheetrefs" "${INTERSHEET_REFS}"
			(at 96.2236 156.2894 0)
			(effects
				(font
					(size 1.27 1.27)
				)
				(justify right)
			)
		)
	)
	(global_label "PCIE2_RST*"
		(shape input)
		(at 113.03 146.05 180)
		(fields_autoplaced yes)
		(effects
			(font
				(size 1.27 1.27)
			)
			(justify right)
		)
		(property "Intersheetrefs" "${INTERSHEET_REFS}"
			(at 99.7312 146.1294 0)
			(effects
				(font
					(size 1.27 1.27)
				)
				(justify right)
			)
		)
	)
	(global_label "I2C2_SCL"
		(shape input)
		(at 328.93 242.57 180)
		(effects
			(font
				(size 1.27 1.27)
			)
			(justify right)
		)
		(property "Intersheetrefs" "${INTERSHEET_REFS}"
			(at 314.96 242.57 0)
			(effects
				(font
					(size 1.27 1.27)
				)
				(justify right)
			)
		)
	)
	(global_label "PCIE2_CLK_N"
		(shape bidirectional)
		(at 372.11 187.96 180)
		(effects
			(font
				(size 1.27 1.27)
			)
			(justify right)
		)
		(property "Intersheetrefs" "${INTERSHEET_REFS}"
			(at 355.6 187.96 0)
			(effects
				(font
					(size 1.27 1.27)
				)
				(justify right)
			)
		)
	)
	(global_label "GPIO11"
		(shape input)
		(at 173.99 161.29 180)
		(fields_autoplaced yes)
		(effects
			(font
				(size 1.27 1.27)
			)
			(justify right)
		)
		(property "Intersheetrefs" "${INTERSHEET_REFS}"
			(at 164.6826 161.2106 0)
			(effects
				(font
					(size 1.27 1.27)
				)
				(justify right)
			)
		)
	)
	(global_label "~{SPI0_CS0}"
		(shape input)
		(at 110.49 194.31 180)
		(fields_autoplaced yes)
		(effects
			(font
				(size 1.27 1.27)
			)
			(justify right)
		)
		(property "Intersheetrefs" "${INTERSHEET_REFS}"
			(at 99.1264 194.2306 0)
			(effects
				(font
					(size 1.27 1.27)
				)
				(justify right)
			)
		)
	)
	(global_label "PCIE2_TX1_N"
		(shape input)
		(at 271.78 38.1 180)
		(effects
			(font
				(size 1.27 1.27)
			)
			(justify right)
		)
		(property "Intersheetrefs" "${INTERSHEET_REFS}"
			(at 253.365 38.1 0)
			(effects
				(font
					(size 1.27 1.27)
				)
				(justify right)
			)
		)
	)
	(global_label "USBC0_FLG"
		(shape input)
		(at 115.57 78.74 0)
		(effects
			(font
				(size 1.27 1.27)
			)
			(justify left)
		)
		(property "Intersheetrefs" "${INTERSHEET_REFS}"
			(at 129.54 78.74 0)
			(effects
				(font
					(size 1.27 1.27)
				)
				(justify left)
			)
		)
	)
	(global_label "SYS_SDA"
		(shape bidirectional)
		(at 93.98 260.35 0)
		(fields_autoplaced yes)
		(effects
			(font
				(size 1.27 1.27)
			)
			(justify left)
		)
		(property "Intersheetrefs" "${INTERSHEET_REFS}"
			(at 106.1198 260.35 0)
			(effects
				(font
					(size 1.27 1.27)
				)
				(justify left)
			)
		)
	)
	(global_label "CSIA_FLG"
		(shape input)
		(at 115.57 71.12 0)
		(effects
			(font
				(size 1.27 1.27)
			)
			(justify left)
		)
		(property "Intersheetrefs" "${INTERSHEET_REFS}"
			(at 129.54 71.12 0)
			(effects
				(font
					(size 1.27 1.27)
				)
				(justify left)
			)
		)
	)
	(global_label "SYS_SDA"
		(shape bidirectional)
		(at 295.91 114.3 180)
		(effects
			(font
				(size 1.27 1.27)
			)
			(justify right)
		)
		(property "Intersheetrefs" "${INTERSHEET_REFS}"
			(at 283.21 114.3 0)
			(effects
				(font
					(size 1.27 1.27)
				)
				(justify right)
			)
		)
	)
	(global_label "USBSS1_TX_N"
		(shape input)
		(at 271.78 60.96 180)
		(effects
			(font
				(size 1.27 1.27)
			)
			(justify right)
		)
		(property "Intersheetrefs" "${INTERSHEET_REFS}"
			(at 255.27 60.96 0)
			(effects
				(font
					(size 1.1 1.1)
				)
				(justify right)
			)
		)
	)
	(global_label "PCIE_WAKE_SEL_EXT"
		(shape input)
		(at 181.61 139.7 180)
		(fields_autoplaced yes)
		(effects
			(font
				(size 1.27 1.27)
			)
			(justify right)
		)
		(property "Intersheetrefs" "${INTERSHEET_REFS}"
			(at 160.3283 139.6206 0)
			(effects
				(font
					(size 1.27 1.27)
				)
				(justify right)
			)
		)
	)
	(global_label "EEPROM_PWR"
		(shape output)
		(at 34.29 232.41 180)
		(fields_autoplaced yes)
		(effects
			(font
				(size 1.27 1.27)
			)
			(justify right)
		)
		(property "Intersheetrefs" "${INTERSHEET_REFS}"
			(at 18.7259 232.41 0)
			(effects
				(font
					(size 1.27 1.27)
				)
				(justify right)
			)
		)
	)
	(global_label "PCIE3_CLK_N"
		(shape bidirectional)
		(at 372.11 218.44 180)
		(effects
			(font
				(size 1.27 1.27)
			)
			(justify right)
		)
		(property "Intersheetrefs" "${INTERSHEET_REFS}"
			(at 355.6 218.44 0)
			(effects
				(font
					(size 1.27 1.27)
				)
				(justify right)
			)
		)
	)
	(global_label "~{SPI1_CS1}"
		(shape input)
		(at 175.26 191.77 180)
		(fields_autoplaced yes)
		(effects
			(font
				(size 1.27 1.27)
			)
			(justify right)
		)
		(property "Intersheetrefs" "${INTERSHEET_REFS}"
			(at 163.8964 191.8494 0)
			(effects
				(font
					(size 1.27 1.27)
				)
				(justify right)
			)
		)
	)
	(global_label "PCIE2_TX0_P"
		(shape input)
		(at 271.78 48.26 180)
		(effects
			(font
				(size 1.27 1.27)
			)
			(justify right)
		)
		(property "Intersheetrefs" "${INTERSHEET_REFS}"
			(at 253.365 48.26 0)
			(effects
				(font
					(size 1.27 1.27)
				)
				(justify right)
			)
		)
	)
	(global_label "3V3_STDB"
		(shape input)
		(at 314.96 166.37 0)
		(fields_autoplaced yes)
		(effects
			(font
				(size 1.27 1.27)
			)
			(justify left)
		)
		(property "Intersheetrefs" "${INTERSHEET_REFS}"
			(at 327.1375 166.37 0)
			(effects
				(font
					(size 1.27 1.27)
				)
				(justify left)
			)
		)
	)
	(global_label "CAN_TX"
		(shape output)
		(at 359.41 121.92 0)
		(effects
			(font
				(size 1.27 1.27)
			)
			(justify left)
		)
		(property "Intersheetrefs" "${INTERSHEET_REFS}"
			(at 373.38 121.92 0)
			(effects
				(font
					(size 1.27 1.27)
				)
				(justify left)
			)
		)
	)
	(global_label "I2C2_SDA"
		(shape bidirectional)
		(at 328.93 240.03 180)
		(effects
			(font
				(size 1.27 1.27)
			)
			(justify right)
		)
		(property "Intersheetrefs" "${INTERSHEET_REFS}"
			(at 314.96 240.03 0)
			(effects
				(font
					(size 1.27 1.27)
				)
				(justify right)
			)
		)
	)
	(global_label "GPIO07"
		(shape input)
		(at 109.22 138.43 180)
		(fields_autoplaced yes)
		(effects
			(font
				(size 1.27 1.27)
			)
			(justify right)
		)
		(property "Intersheetrefs" "${INTERSHEET_REFS}"
			(at 99.9126 138.5094 0)
			(effects
				(font
					(size 1.27 1.27)
				)
				(justify right)
			)
		)
	)
	(global_label "PDC_MISO"
		(shape input)
		(at 99.06 240.03 0)
		(fields_autoplaced yes)
		(effects
			(font
				(size 1.27 1.27)
			)
			(justify left)
		)
		(property "Intersheetrefs" "${INTERSHEET_REFS}"
			(at 111.419 240.03 0)
			(effects
				(font
					(size 1.27 1.27)
				)
				(justify left)
			)
		)
	)
	(global_label "USBSS1_RX_N"
		(shape output)
		(at 342.9 63.5 0)
		(effects
			(font
				(size 1.27 1.27)
			)
			(justify left)
		)
		(property "Intersheetrefs" "${INTERSHEET_REFS}"
			(at 359.41 63.5 0)
			(effects
				(font
					(size 1.1 1.1)
				)
				(justify left)
			)
		)
	)
	(global_label "GPIO01"
		(shape input)
		(at 109.22 140.97 180)
		(fields_autoplaced yes)
		(effects
			(font
				(size 1.27 1.27)
			)
			(justify right)
		)
		(property "Intersheetrefs" "${INTERSHEET_REFS}"
			(at 99.9126 141.0494 0)
			(effects
				(font
					(size 1.27 1.27)
				)
				(justify right)
			)
		)
	)
	(global_label "SYS_SCL"
		(shape input)
		(at 295.91 116.84 180)
		(effects
			(font
				(size 1.27 1.27)
			)
			(justify right)
		)
		(property "Intersheetrefs" "${INTERSHEET_REFS}"
			(at 283.21 116.84 0)
			(effects
				(font
					(size 1.27 1.27)
				)
				(justify right)
			)
		)
	)
	(global_label "PCIE2_CLK_N"
		(shape input)
		(at 271.78 53.34 180)
		(effects
			(font
				(size 1.27 1.27)
			)
			(justify right)
		)
		(property "Intersheetrefs" "${INTERSHEET_REFS}"
			(at 253.365 53.34 0)
			(effects
				(font
					(size 1.27 1.27)
				)
				(justify right)
			)
		)
	)
	(global_label "PCIE2_RX0_P"
		(shape output)
		(at 342.9 50.8 0)
		(effects
			(font
				(size 1.27 1.27)
			)
			(justify left)
		)
		(property "Intersheetrefs" "${INTERSHEET_REFS}"
			(at 361.315 50.8 0)
			(effects
				(font
					(size 1.27 1.27)
				)
				(justify left)
			)
		)
	)
	(global_label "PCIE2_RX1_P"
		(shape output)
		(at 342.9 43.18 0)
		(effects
			(font
				(size 1.27 1.27)
			)
			(justify left)
		)
		(property "Intersheetrefs" "${INTERSHEET_REFS}"
			(at 361.315 43.18 0)
			(effects
				(font
					(size 1.27 1.27)
				)
				(justify left)
			)
		)
	)
	(global_label "USER_LED1"
		(shape input)
		(at 196.85 251.46 180)
		(effects
			(font
				(size 1.27 1.27)
			)
			(justify right)
		)
		(property "Intersheetrefs" "${INTERSHEET_REFS}"
			(at 183.515 251.46 0)
			(effects
				(font
					(size 1.27 1.27)
				)
				(justify right)
			)
		)
	)
	(global_label "~{SPI0_CS1}"
		(shape input)
		(at 110.49 191.77 180)
		(fields_autoplaced yes)
		(effects
			(font
				(size 1.27 1.27)
			)
			(justify right)
		)
		(property "Intersheetrefs" "${INTERSHEET_REFS}"
			(at 99.1264 191.6906 0)
			(effects
				(font
					(size 1.27 1.27)
				)
				(justify right)
			)
		)
	)
	(global_label "I2C2_SCL"
		(shape input)
		(at 359.41 116.84 0)
		(effects
			(font
				(size 1.27 1.27)
			)
			(justify left)
		)
		(property "Intersheetrefs" "${INTERSHEET_REFS}"
			(at 373.38 116.84 0)
			(effects
				(font
					(size 1.27 1.27)
				)
				(justify left)
			)
		)
	)
	(global_label "PCIE2_CLKREQ*"
		(shape input)
		(at 116.84 143.51 180)
		(fields_autoplaced yes)
		(effects
			(font
				(size 1.27 1.27)
			)
			(justify right)
		)
		(property "Intersheetrefs" "${INTERSHEET_REFS}"
			(at 99.6707 143.5894 0)
			(effects
				(font
					(size 1.27 1.27)
				)
				(justify right)
			)
		)
	)
	(global_label "PCIE3_CLK_P"
		(shape bidirectional)
		(at 342.9 58.42 0)
		(effects
			(font
				(size 1.27 1.27)
			)
			(justify left)
		)
		(property "Intersheetrefs" "${INTERSHEET_REFS}"
			(at 361.315 58.42 0)
			(effects
				(font
					(size 1.27 1.27)
				)
				(justify left)
			)
		)
	)
	(global_label "PCIE2_RX1_N"
		(shape bidirectional)
		(at 372.11 198.12 180)
		(effects
			(font
				(size 1.27 1.27)
			)
			(justify right)
		)
		(property "Intersheetrefs" "${INTERSHEET_REFS}"
			(at 355.6 198.12 0)
			(effects
				(font
					(size 1.27 1.27)
				)
				(justify right)
			)
		)
	)
	(global_label "PCIE2_RX0_N"
		(shape output)
		(at 342.9 48.26 0)
		(effects
			(font
				(size 1.27 1.27)
			)
			(justify left)
		)
		(property "Intersheetrefs" "${INTERSHEET_REFS}"
			(at 361.315 48.26 0)
			(effects
				(font
					(size 1.27 1.27)
				)
				(justify left)
			)
		)
	)
	(global_label "SYS_SDA"
		(shape bidirectional)
		(at 38.1 71.12 180)
		(fields_autoplaced yes)
		(effects
			(font
				(size 1.27 1.27)
			)
			(justify right)
		)
		(property "Intersheetrefs" "${INTERSHEET_REFS}"
			(at 25.9602 71.12 0)
			(effects
				(font
					(size 1.27 1.27)
				)
				(justify right)
			)
		)
	)
	(symbol
		(lib_id "antmicroCapacitors0402:C_100n_0402")
		(at 285.75 63.5 180)
		(unit 1)
		(exclude_from_sim no)
		(in_bom yes)
		(on_board yes)
		(dnp no)
		(property "Reference" "C111"
			(at 284.48 62.865 0)
			(effects
				(font
					(size 1.27 1.27)
				)
				(justify right top)
			)
		)
		(property "Value" "C_100n_0402"
			(at 265.43 53.34 0)
			(effects
				(font
					(size 1.27 1.27)
					(thickness 0.15)
				)
				(justify left bottom)
				(hide yes)
			)
		)
		(property "Footprint" "antmicro-footprints:C_0402_1005Metric"
			(at 265.43 50.8 0)
			(effects
				(font
					(size 1.27 1.27)
					(thickness 0.15)
				)
				(justify left bottom)
				(hide yes)
			)
		)
		(property "Datasheet" "https://www.murata.com/products/productdetail?partno=GRM155R61H104KE14%23"
			(at 265.43 48.26 0)
			(effects
				(font
					(size 1.27 1.27)
					(thickness 0.15)
				)
				(justify left bottom)
				(hide yes)
			)
		)
		(property "Description" ""
			(at 285.75 63.5 0)
			(effects
				(font
					(size 1.27 1.27)
				)
				(hide yes)
			)
		)
		(property "Manufacturer" "Murata"
			(at 265.43 43.18 0)
			(effects
				(font
					(size 1.27 1.27)
					(thickness 0.15)
				)
				(justify left bottom)
				(hide yes)
			)
		)
		(property "MPN" "GRM155R61H104KE14D"
			(at 265.43 45.72 0)
			(effects
				(font
					(size 1.27 1.27)
					(thickness 0.15)
				)
				(justify left bottom)
				(hide yes)
			)
		)
		(property "Val" "100n"
			(at 281.94 64.135 0)
			(effects
				(font
					(size 1.27 1.27)
					(thickness 0.15)
				)
				(justify left bottom)
			)
		)
		(property "License" "Apache-2.0"
			(at 265.43 40.64 0)
			(effects
				(font
					(size 1.27 1.27)
					(thickness 0.15)
				)
				(justify left bottom)
				(hide yes)
			)
		)
		(property "Author" "Antmicro"
			(at 265.43 38.1 0)
			(effects
				(font
					(size 1.27 1.27)
					(thickness 0.15)
				)
				(justify left bottom)
				(hide yes)
			)
		)
		(property "Voltage" "50V"
			(at 265.43 35.56 0)
			(effects
				(font
					(size 1.27 1.27)
				)
				(justify left bottom)
				(hide yes)
			)
		)
		(property "Dielectric" "X5R"
			(at 265.43 33.02 0)
			(effects
				(font
					(size 1.27 1.27)
				)
				(justify left bottom)
				(hide yes)
			)
		)
		(pin "1"
		)
		(pin "2"
		)
		(instances
			(project "jetson-orin-baseboard"
				(path ""
					(reference "C111")
					(unit 1)
				)
			)
		)
	)
	(symbol
		(lib_id "antmicroCapacitors0402:C_220n_0402")
		(at 285.75 40.64 180)
		(unit 1)
		(exclude_from_sim no)
		(in_bom yes)
		(on_board yes)
		(dnp no)
		(property "Reference" "C110"
			(at 284.48 40.005 0)
			(effects
				(font
					(size 1.27 1.27)
				)
				(justify right top)
			)
		)
		(property "Value" "C_220n_0402"
			(at 265.43 30.48 0)
			(effects
				(font
					(size 1.27 1.27)
					(thickness 0.15)
				)
				(justify left bottom)
				(hide yes)
			)
		)
		(property "Footprint" "antmicro-footprints:C_0402_1005Metric"
			(at 265.43 27.94 0)
			(effects
				(font
					(size 1.27 1.27)
					(thickness 0.15)
				)
				(justify left bottom)
				(hide yes)
			)
		)
		(property "Datasheet" "https://www.yageo.com/en/Chart/Download/pdf/CC0402KRX5R6BB224"
			(at 265.43 25.4 0)
			(effects
				(font
					(size 1.27 1.27)
					(thickness 0.15)
				)
				(justify left bottom)
				(hide yes)
			)
		)
		(property "Description" ""
			(at 285.75 40.64 0)
			(effects
				(font
					(size 1.27 1.27)
				)
				(hide yes)
			)
		)
		(property "Manufacturer" "YAGEO"
			(at 265.43 20.32 0)
			(effects
				(font
					(size 1.27 1.27)
					(thickness 0.15)
				)
				(justify left bottom)
				(hide yes)
			)
		)
		(property "MPN" "CC0402KRX5R6BB224"
			(at 265.43 22.86 0)
			(effects
				(font
					(size 1.27 1.27)
					(thickness 0.15)
				)
				(justify left bottom)
				(hide yes)
			)
		)
		(property "Val" "220n"
			(at 281.94 48.895 0)
			(effects
				(font
					(size 1.27 1.27)
					(thickness 0.15)
				)
				(justify left bottom)
			)
		)
		(property "License" "Apache-2.0"
			(at 265.43 17.78 0)
			(effects
				(font
					(size 1.27 1.27)
					(thickness 0.15)
				)
				(justify left bottom)
				(hide yes)
			)
		)
		(property "Author" "Antmicro"
			(at 265.43 15.24 0)
			(effects
				(font
					(size 1.27 1.27)
					(thickness 0.15)
				)
				(justify left bottom)
				(hide yes)
			)
		)
		(property "Voltage" ""
			(at 265.43 12.7 0)
			(effects
				(font
					(size 1.27 1.27)
				)
				(justify left bottom)
				(hide yes)
			)
		)
		(property "Dielectric" ""
			(at 265.43 10.16 0)
			(effects
				(font
					(size 1.27 1.27)
				)
				(justify left bottom)
				(hide yes)
			)
		)
		(pin "1"
		)
		(pin "2"
		)
		(instances
			(project "jetson-orin-baseboard"
				(path ""
					(reference "C110")
					(unit 1)
				)
			)
		)
	)
	(symbol
		(lib_id "antmicroPushbuttonSwitches:SW_KMR211NGLFS_SMD")
		(at 267.97 233.68 270)
		(unit 1)
		(exclude_from_sim no)
		(in_bom yes)
		(on_board yes)
		(dnp no)
		(property "Reference" "S2"
			(at 271.78 237.49 90)
			(effects
				(font
					(size 1.27 1.27)
				)
				(justify left)
			)
		)
		(property "Value" "SW_KMR211NGLFS_SMD"
			(at 260.35 259.08 0)
			(effects
				(font
					(size 1.27 1.27)
					(thickness 0.15)
				)
				(justify left bottom)
				(hide yes)
			)
		)
		(property "Footprint" "antmicro-footprints:SW_KMR211NGLFS_SMD"
			(at 257.81 259.08 0)
			(effects
				(font
					(size 1.27 1.27)
					(thickness 0.15)
				)
				(justify left bottom)
				(hide yes)
			)
		)
		(property "Datasheet" "http://www.farnell.com/datasheets/2631211.pdf"
			(at 255.27 259.08 0)
			(effects
				(font
					(size 1.27 1.27)
					(thickness 0.15)
				)
				(justify left bottom)
				(hide yes)
			)
		)
		(property "Description" ""
			(at 267.97 233.68 0)
			(effects
				(font
					(size 1.27 1.27)
				)
				(hide yes)
			)
		)
		(property "MPN" "KMR211NGLFS"
			(at 271.78 240.03 90)
			(effects
				(font
					(size 1.27 1.27)
					(thickness 0.15)
				)
				(justify left)
			)
		)
		(property "Manufacturer" "C&K"
			(at 252.73 259.08 0)
			(effects
				(font
					(size 1.27 1.27)
					(thickness 0.15)
				)
				(justify left bottom)
				(hide yes)
			)
		)
		(property "Author" "Antmicro"
			(at 250.19 259.08 0)
			(effects
				(font
					(size 1.27 1.27)
					(thickness 0.15)
				)
				(justify left bottom)
				(hide yes)
			)
		)
		(property "License" "Apache-2.0"
			(at 247.65 259.08 0)
			(effects
				(font
					(size 1.27 1.27)
					(thickness 0.15)
				)
				(justify left bottom)
				(hide yes)
			)
		)
		(pin "1"
		)
		(pin "2"
		)
		(pin "3"
		)
		(pin "4"
		)
		(instances
			(project "jetson-orin-baseboard"
				(path ""
					(reference "S2")
					(unit 1)
				)
			)
		)
	)
	(symbol
		(lib_id "antmicropower:GND")
		(at 62.23 157.48 0)
		(unit 1)
		(exclude_from_sim no)
		(in_bom yes)
		(on_board yes)
		(dnp no)
		(fields_autoplaced yes)
		(property "Reference" "#PWR0223"
			(at 62.23 163.83 0)
			(effects
				(font
					(size 1.27 1.27)
				)
				(justify left bottom)
				(hide yes)
			)
		)
		(property "Value" "GND"
			(at 62.23 161.29 0)
			(effects
				(font
					(size 1.27 1.27)
					(thickness 0.15)
				)
			)
		)
		(property "Footprint" ""
			(at 71.12 165.1 0)
			(effects
				(font
					(size 1.27 1.27)
					(thickness 0.15)
				)
				(justify left bottom)
				(hide yes)
			)
		)
		(property "Datasheet" ""
			(at 71.12 170.18 0)
			(effects
				(font
					(size 1.27 1.27)
					(thickness 0.15)
				)
				(justify left bottom)
				(hide yes)
			)
		)
		(property "Description" ""
			(at 62.23 157.48 0)
			(effects
				(font
					(size 1.27 1.27)
				)
				(hide yes)
			)
		)
		(property "Author" "Antmicro"
			(at 71.12 165.1 0)
			(effects
				(font
					(size 1.27 1.27)
					(thickness 0.15)
				)
				(justify left bottom)
				(hide yes)
			)
		)
		(property "License" "Apache-2.0"
			(at 71.12 167.64 0)
			(effects
				(font
					(size 1.27 1.27)
					(thickness 0.15)
				)
				(justify left bottom)
				(hide yes)
			)
		)
		(pin "1"
		)
		(instances
			(project "jetson-orin-baseboard"
				(path ""
					(reference "#PWR0223")
					(unit 1)
				)
			)
		)
	)
	(symbol
		(lib_id "antmicroResistorNetworksArrays:R_4x330R_0402_array")
		(at 132.08 191.77 0)
		(mirror y)
		(unit 1)
		(exclude_from_sim no)
		(in_bom yes)
		(on_board yes)
		(dnp no)
		(property "Reference" "R63"
			(at 127 186.055 0)
			(effects
				(font
					(size 1.27 1.27)
				)
			)
		)
		(property "Value" "R_4x330R_0402_array"
			(at 105.41 196.85 0)
			(effects
				(font
					(size 1.27 1.27)
					(thickness 0.15)
				)
				(justify left bottom)
				(hide yes)
			)
		)
		(property "Footprint" "antmicro-footprints:R_Array_4x0402"
			(at 105.41 201.93 0)
			(effects
				(font
					(size 1.27 1.27)
					(thickness 0.15)
				)
				(justify left bottom)
				(hide yes)
			)
		)
		(property "Datasheet" "http://industrial.panasonic.com/cdbs/www-data/pdf/AOC0000/AOC0000C14.pdf"
			(at 105.41 204.47 0)
			(effects
				(font
					(size 1.27 1.27)
					(thickness 0.15)
				)
				(justify left bottom)
				(hide yes)
			)
		)
		(property "Description" ""
			(at 132.08 191.77 0)
			(effects
				(font
					(size 1.27 1.27)
				)
				(hide yes)
			)
		)
		(property "MPN" "EXB-28V331JX"
			(at 105.41 207.01 0)
			(effects
				(font
					(size 1.27 1.27)
					(thickness 0.15)
				)
				(justify left bottom)
				(hide yes)
			)
		)
		(property "Manufacturer" "Panasonic"
			(at 105.41 209.55 0)
			(effects
				(font
					(size 1.27 1.27)
					(thickness 0.15)
				)
				(justify left bottom)
				(hide yes)
			)
		)
		(property "Author" "Antmicro"
			(at 105.41 212.09 0)
			(effects
				(font
					(size 1.27 1.27)
					(thickness 0.15)
				)
				(justify left bottom)
				(hide yes)
			)
		)
		(property "License" "Apache-2.0"
			(at 105.41 214.63 0)
			(effects
				(font
					(size 1.27 1.27)
					(thickness 0.15)
				)
				(justify left bottom)
				(hide yes)
			)
		)
		(property "Val" "R_4x330R_0402"
			(at 127 188.595 0)
			(effects
				(font
					(size 1.27 1.27)
				)
			)
		)
		(pin "1"
		)
		(pin "2"
		)
		(pin "3"
		)
		(pin "4"
		)
		(pin "5"
		)
		(pin "6"
		)
		(pin "7"
		)
		(pin "8"
		)
		(instances
			(project "jetson-orin-baseboard"
				(path ""
					(reference "R63")
					(unit 1)
				)
			)
		)
	)
	(symbol
		(lib_id "antmicroResistorNetworksArrays:R_4x330R_0402_array")
		(at 132.08 138.43 0)
		(mirror y)
		(unit 1)
		(exclude_from_sim no)
		(in_bom yes)
		(on_board yes)
		(dnp no)
		(property "Reference" "R26"
			(at 127 132.715 0)
			(effects
				(font
					(size 1.27 1.27)
				)
			)
		)
		(property "Value" "R_4x330R_0402_array"
			(at 105.41 143.51 0)
			(effects
				(font
					(size 1.27 1.27)
					(thickness 0.15)
				)
				(justify left bottom)
				(hide yes)
			)
		)
		(property "Footprint" "antmicro-footprints:R_Array_4x0402"
			(at 105.41 148.59 0)
			(effects
				(font
					(size 1.27 1.27)
					(thickness 0.15)
				)
				(justify left bottom)
				(hide yes)
			)
		)
		(property "Datasheet" "http://industrial.panasonic.com/cdbs/www-data/pdf/AOC0000/AOC0000C14.pdf"
			(at 105.41 151.13 0)
			(effects
				(font
					(size 1.27 1.27)
					(thickness 0.15)
				)
				(justify left bottom)
				(hide yes)
			)
		)
		(property "Description" ""
			(at 132.08 138.43 0)
			(effects
				(font
					(size 1.27 1.27)
				)
				(hide yes)
			)
		)
		(property "MPN" "EXB-28V331JX"
			(at 105.41 153.67 0)
			(effects
				(font
					(size 1.27 1.27)
					(thickness 0.15)
				)
				(justify left bottom)
				(hide yes)
			)
		)
		(property "Manufacturer" "Panasonic"
			(at 105.41 156.21 0)
			(effects
				(font
					(size 1.27 1.27)
					(thickness 0.15)
				)
				(justify left bottom)
				(hide yes)
			)
		)
		(property "Author" "Antmicro"
			(at 105.41 158.75 0)
			(effects
				(font
					(size 1.27 1.27)
					(thickness 0.15)
				)
				(justify left bottom)
				(hide yes)
			)
		)
		(property "License" "Apache-2.0"
			(at 105.41 161.29 0)
			(effects
				(font
					(size 1.27 1.27)
					(thickness 0.15)
				)
				(justify left bottom)
				(hide yes)
			)
		)
		(property "Val" "R_4x330R_0402"
			(at 127 135.255 0)
			(effects
				(font
					(size 1.27 1.27)
				)
			)
		)
		(pin "1"
		)
		(pin "2"
		)
		(pin "3"
		)
		(pin "4"
		)
		(pin "5"
		)
		(pin "6"
		)
		(pin "7"
		)
		(pin "8"
		)
		(instances
			(project "jetson-orin-baseboard"
				(path ""
					(reference "R26")
					(unit 1)
				)
			)
		)
	)
	(symbol
		(lib_id "antmicropower:GND")
		(at 191.77 97.79 0)
		(unit 1)
		(exclude_from_sim no)
		(in_bom yes)
		(on_board yes)
		(dnp no)
		(fields_autoplaced yes)
		(property "Reference" "#PWR0210"
			(at 191.77 104.14 0)
			(effects
				(font
					(size 1.27 1.27)
				)
				(justify left bottom)
				(hide yes)
			)
		)
		(property "Value" "GND"
			(at 191.77 101.6 0)
			(effects
				(font
					(size 1.27 1.27)
					(thickness 0.15)
				)
			)
		)
		(property "Footprint" ""
			(at 200.66 105.41 0)
			(effects
				(font
					(size 1.27 1.27)
					(thickness 0.15)
				)
				(justify left bottom)
				(hide yes)
			)
		)
		(property "Datasheet" ""
			(at 200.66 110.49 0)
			(effects
				(font
					(size 1.27 1.27)
					(thickness 0.15)
				)
				(justify left bottom)
				(hide yes)
			)
		)
		(property "Description" ""
			(at 191.77 97.79 0)
			(effects
				(font
					(size 1.27 1.27)
				)
				(hide yes)
			)
		)
		(property "Author" "Antmicro"
			(at 200.66 105.41 0)
			(effects
				(font
					(size 1.27 1.27)
					(thickness 0.15)
				)
				(justify left bottom)
				(hide yes)
			)
		)
		(property "License" "Apache-2.0"
			(at 200.66 107.95 0)
			(effects
				(font
					(size 1.27 1.27)
					(thickness 0.15)
				)
				(justify left bottom)
				(hide yes)
			)
		)
		(pin "1"
		)
		(instances
			(project "jetson-orin-baseboard"
				(path ""
					(reference "#PWR0210")
					(unit 1)
				)
			)
		)
	)
	(symbol
		(lib_id "antmicroResistorNetworksArrays:R_4x330R_0402_array")
		(at 199.39 199.39 180)
		(unit 1)
		(exclude_from_sim no)
		(in_bom yes)
		(on_board yes)
		(dnp no)
		(property "Reference" "R102"
			(at 194.31 186.055 0)
			(effects
				(font
					(size 1.27 1.27)
				)
			)
		)
		(property "Value" "R_4x330R_0402_array"
			(at 172.72 194.31 0)
			(effects
				(font
					(size 1.27 1.27)
					(thickness 0.15)
				)
				(justify left bottom)
				(hide yes)
			)
		)
		(property "Footprint" "antmicro-footprints:R_Array_4x0402"
			(at 172.72 189.23 0)
			(effects
				(font
					(size 1.27 1.27)
					(thickness 0.15)
				)
				(justify left bottom)
				(hide yes)
			)
		)
		(property "Datasheet" "http://industrial.panasonic.com/cdbs/www-data/pdf/AOC0000/AOC0000C14.pdf"
			(at 172.72 186.69 0)
			(effects
				(font
					(size 1.27 1.27)
					(thickness 0.15)
				)
				(justify left bottom)
				(hide yes)
			)
		)
		(property "Description" ""
			(at 199.39 199.39 0)
			(effects
				(font
					(size 1.27 1.27)
				)
				(hide yes)
			)
		)
		(property "MPN" "EXB-28V331JX"
			(at 172.72 184.15 0)
			(effects
				(font
					(size 1.27 1.27)
					(thickness 0.15)
				)
				(justify left bottom)
				(hide yes)
			)
		)
		(property "Manufacturer" "Panasonic"
			(at 172.72 181.61 0)
			(effects
				(font
					(size 1.27 1.27)
					(thickness 0.15)
				)
				(justify left bottom)
				(hide yes)
			)
		)
		(property "Author" "Antmicro"
			(at 172.72 179.07 0)
			(effects
				(font
					(size 1.27 1.27)
					(thickness 0.15)
				)
				(justify left bottom)
				(hide yes)
			)
		)
		(property "License" "Apache-2.0"
			(at 172.72 176.53 0)
			(effects
				(font
					(size 1.27 1.27)
					(thickness 0.15)
				)
				(justify left bottom)
				(hide yes)
			)
		)
		(property "Val" "R_4x330R_0402"
			(at 194.31 188.595 0)
			(effects
				(font
					(size 1.27 1.27)
				)
			)
		)
		(pin "1"
		)
		(pin "2"
		)
		(pin "3"
		)
		(pin "4"
		)
		(pin "5"
		)
		(pin "6"
		)
		(pin "7"
		)
		(pin "8"
		)
		(instances
			(project "jetson-orin-baseboard"
				(path ""
					(reference "R102")
					(unit 1)
				)
			)
		)
	)
	(symbol
		(lib_id "antmicropower:+5V")
		(at 73.66 148.59 0)
		(unit 1)
		(exclude_from_sim no)
		(in_bom yes)
		(on_board yes)
		(dnp no)
		(property "Reference" "#PWR0228"
			(at 73.66 152.4 0)
			(effects
				(font
					(size 1.27 1.27)
				)
				(justify left bottom)
				(hide yes)
			)
		)
		(property "Value" "+5V"
			(at 71.755 145.415 0)
			(effects
				(font
					(size 1.27 1.27)
					(thickness 0.15)
				)
				(justify left bottom)
			)
		)
		(property "Footprint" ""
			(at 88.9 156.21 0)
			(effects
				(font
					(size 1.27 1.27)
					(thickness 0.15)
				)
				(justify left bottom)
				(hide yes)
			)
		)
		(property "Datasheet" ""
			(at 88.9 158.75 0)
			(effects
				(font
					(size 1.27 1.27)
					(thickness 0.15)
				)
				(justify left bottom)
				(hide yes)
			)
		)
		(property "Description" ""
			(at 73.66 148.59 0)
			(effects
				(font
					(size 1.27 1.27)
				)
				(hide yes)
			)
		)
		(property "Author" "Antmicro"
			(at 88.9 156.21 0)
			(effects
				(font
					(size 1.27 1.27)
					(thickness 0.15)
				)
				(justify left bottom)
				(hide yes)
			)
		)
		(property "License" "Apache-2.0"
			(at 88.9 158.75 0)
			(effects
				(font
					(size 1.27 1.27)
					(thickness 0.15)
				)
				(justify left bottom)
				(hide yes)
			)
		)
		(pin "1"
		)
		(instances
			(project "jetson-orin-baseboard"
				(path ""
					(reference "#PWR0228")
					(unit 1)
				)
			)
		)
	)
	(symbol
		(lib_id "antmicroTVSDiodes:TPD1E0B04_XDFN-2")
		(at 388.62 182.88 0)
		(unit 1)
		(exclude_from_sim no)
		(in_bom yes)
		(on_board yes)
		(dnp no)
		(property "Reference" "D42"
			(at 393.065 182.245 0)
			(effects
				(font
					(size 1.27 1.27)
				)
				(justify left bottom)
			)
		)
		(property "Value" "TPD1E0B04_XDFN-2"
			(at 403.86 193.04 0)
			(effects
				(font
					(size 1.27 1.27)
					(thickness 0.15)
				)
				(justify left bottom)
				(hide yes)
			)
		)
		(property "Footprint" "antmicro-footprints:XDFN-2_1x0.60mm"
			(at 403.86 187.96 0)
			(effects
				(font
					(size 1.27 1.27)
					(thickness 0.15)
				)
				(justify left bottom)
				(hide yes)
			)
		)
		(property "Datasheet" "https://www.ti.com/general/docs/suppproductinfo.tsp?distId=26&gotoUrl=https://www.ti.com/lit/gpn/tpd1e0b04"
			(at 403.86 190.5 0)
			(effects
				(font
					(size 1.27 1.27)
					(thickness 0.15)
				)
				(justify left bottom)
				(hide yes)
			)
		)
		(property "Description" ""
			(at 388.62 182.88 0)
			(effects
				(font
					(size 1.27 1.27)
				)
				(hide yes)
			)
		)
		(property "Manufacturer" "Texas Instruments"
			(at 403.86 195.58 0)
			(effects
				(font
					(size 1.27 1.27)
					(thickness 0.15)
				)
				(justify left bottom)
				(hide yes)
			)
		)
		(property "MPN" "TPD1E0B04DPYR"
			(at 373.38 182.245 0)
			(effects
				(font
					(size 1.27 1.27)
					(thickness 0.15)
				)
				(justify left bottom)
			)
		)
		(property "Author" "Antmicro"
			(at 403.86 198.12 0)
			(effects
				(font
					(size 1.27 1.27)
					(thickness 0.15)
				)
				(justify left bottom)
				(hide yes)
			)
		)
		(property "License" "Apache-2.0"
			(at 403.86 200.66 0)
			(effects
				(font
					(size 1.27 1.27)
					(thickness 0.15)
				)
				(justify left bottom)
				(hide yes)
			)
		)
		(pin "1"
		)
		(pin "2"
		)
		(instances
			(project "jetson-orin-baseboard"
				(path ""
					(reference "D42")
					(unit 1)
				)
			)
		)
	)
	(symbol
		(lib_id "antmicroDiodesRectifiersSingle:RB521S30T1G")
		(at 63.5 257.81 0)
		(unit 1)
		(exclude_from_sim no)
		(in_bom yes)
		(on_board yes)
		(dnp no)
		(property "Reference" "D63"
			(at 66.04 251.46 0)
			(effects
				(font
					(size 1.27 1.27)
					(thickness 0.15)
				)
			)
		)
		(property "Value" "RB521S30T1G"
			(at 86.36 273.05 0)
			(effects
				(font
					(size 1.27 1.27)
					(thickness 0.15)
				)
				(justify left bottom)
				(hide yes)
			)
		)
		(property "Footprint" "antmicro-footprints:SOD-523"
			(at 86.36 267.97 0)
			(effects
				(font
					(size 1.27 1.27)
					(thickness 0.15)
				)
				(justify left bottom)
				(hide yes)
			)
		)
		(property "Datasheet" "https://www.onsemi.com/pdf/datasheet/rb521s30t1-d.pdf"
			(at 86.36 270.51 0)
			(effects
				(font
					(size 1.27 1.27)
					(thickness 0.15)
				)
				(justify left bottom)
				(hide yes)
			)
		)
		(property "Description" ""
			(at 63.5 257.81 0)
			(effects
				(font
					(size 1.27 1.27)
				)
				(hide yes)
			)
		)
		(property "MPN" "RB521S30T1G"
			(at 66.04 254 0)
			(effects
				(font
					(size 1.27 1.27)
					(thickness 0.15)
				)
			)
		)
		(property "Manufacturer" "ON Semiconductor"
			(at 86.36 275.59 0)
			(effects
				(font
					(size 1.27 1.27)
					(thickness 0.15)
				)
				(justify left bottom)
				(hide yes)
			)
		)
		(property "Author" "Antmicro"
			(at 86.36 278.13 0)
			(effects
				(font
					(size 1.27 1.27)
					(thickness 0.15)
				)
				(justify left bottom)
				(hide yes)
			)
		)
		(property "License" "Apache-2.0"
			(at 86.36 280.67 0)
			(effects
				(font
					(size 1.27 1.27)
					(thickness 0.15)
				)
				(justify left bottom)
				(hide yes)
			)
		)
		(pin "1"
		)
		(pin "2"
		)
		(instances
			(project "jetson-orin-baseboard"
				(path ""
					(reference "D63")
					(unit 1)
				)
			)
		)
	)
	(symbol
		(lib_id "antmicropower:GND")
		(at 189.23 55.88 0)
		(unit 1)
		(exclude_from_sim no)
		(in_bom yes)
		(on_board yes)
		(dnp no)
		(fields_autoplaced yes)
		(property "Reference" "#PWR0212"
			(at 189.23 62.23 0)
			(effects
				(font
					(size 1.27 1.27)
				)
				(justify left bottom)
				(hide yes)
			)
		)
		(property "Value" "GND"
			(at 189.23 59.69 0)
			(effects
				(font
					(size 1.27 1.27)
					(thickness 0.15)
				)
			)
		)
		(property "Footprint" ""
			(at 198.12 63.5 0)
			(effects
				(font
					(size 1.27 1.27)
					(thickness 0.15)
				)
				(justify left bottom)
				(hide yes)
			)
		)
		(property "Datasheet" ""
			(at 198.12 68.58 0)
			(effects
				(font
					(size 1.27 1.27)
					(thickness 0.15)
				)
				(justify left bottom)
				(hide yes)
			)
		)
		(property "Description" ""
			(at 189.23 55.88 0)
			(effects
				(font
					(size 1.27 1.27)
				)
				(hide yes)
			)
		)
		(property "Author" "Antmicro"
			(at 198.12 63.5 0)
			(effects
				(font
					(size 1.27 1.27)
					(thickness 0.15)
				)
				(justify left bottom)
				(hide yes)
			)
		)
		(property "License" "Apache-2.0"
			(at 198.12 66.04 0)
			(effects
				(font
					(size 1.27 1.27)
					(thickness 0.15)
				)
				(justify left bottom)
				(hide yes)
			)
		)
		(pin "1"
		)
		(instances
			(project "jetson-orin-baseboard"
				(path ""
					(reference "#PWR0212")
					(unit 1)
				)
			)
		)
	)
	(symbol
		(lib_id "antmicroCapacitors0402:C_220n_0402")
		(at 281.94 38.1 180)
		(unit 1)
		(exclude_from_sim no)
		(in_bom yes)
		(on_board yes)
		(dnp no)
		(property "Reference" "C112"
			(at 280.67 37.465 0)
			(effects
				(font
					(size 1.27 1.27)
				)
				(justify right top)
			)
		)
		(property "Value" "C_220n_0402"
			(at 261.62 27.94 0)
			(effects
				(font
					(size 1.27 1.27)
					(thickness 0.15)
				)
				(justify left bottom)
				(hide yes)
			)
		)
		(property "Footprint" "antmicro-footprints:C_0402_1005Metric"
			(at 261.62 25.4 0)
			(effects
				(font
					(size 1.27 1.27)
					(thickness 0.15)
				)
				(justify left bottom)
				(hide yes)
			)
		)
		(property "Datasheet" "https://www.yageo.com/en/Chart/Download/pdf/CC0402KRX5R6BB224"
			(at 261.62 22.86 0)
			(effects
				(font
					(size 1.27 1.27)
					(thickness 0.15)
				)
				(justify left bottom)
				(hide yes)
			)
		)
		(property "Description" ""
			(at 281.94 38.1 0)
			(effects
				(font
					(size 1.27 1.27)
				)
				(hide yes)
			)
		)
		(property "Manufacturer" "YAGEO"
			(at 261.62 17.78 0)
			(effects
				(font
					(size 1.27 1.27)
					(thickness 0.15)
				)
				(justify left bottom)
				(hide yes)
			)
		)
		(property "MPN" "CC0402KRX5R6BB224"
			(at 261.62 20.32 0)
			(effects
				(font
					(size 1.27 1.27)
					(thickness 0.15)
				)
				(justify left bottom)
				(hide yes)
			)
		)
		(property "Val" "220n"
			(at 278.13 38.735 0)
			(effects
				(font
					(size 1.27 1.27)
					(thickness 0.15)
				)
				(justify left bottom)
			)
		)
		(property "License" "Apache-2.0"
			(at 261.62 15.24 0)
			(effects
				(font
					(size 1.27 1.27)
					(thickness 0.15)
				)
				(justify left bottom)
				(hide yes)
			)
		)
		(property "Author" "Antmicro"
			(at 261.62 12.7 0)
			(effects
				(font
					(size 1.27 1.27)
					(thickness 0.15)
				)
				(justify left bottom)
				(hide yes)
			)
		)
		(property "Voltage" ""
			(at 261.62 10.16 0)
			(effects
				(font
					(size 1.27 1.27)
				)
				(justify left bottom)
				(hide yes)
			)
		)
		(property "Dielectric" ""
			(at 261.62 7.62 0)
			(effects
				(font
					(size 1.27 1.27)
				)
				(justify left bottom)
				(hide yes)
			)
		)
		(pin "1"
		)
		(pin "2"
		)
		(instances
			(project "jetson-orin-baseboard"
				(path ""
					(reference "C112")
					(unit 1)
				)
			)
		)
	)
	(symbol
		(lib_id "antmicroResistors0603:R_0R_0603")
		(at 312.42 173.99 90)
		(unit 1)
		(exclude_from_sim no)
		(in_bom yes)
		(on_board yes)
		(dnp no)
		(fields_autoplaced yes)
		(property "Reference" "R247"
			(at 314.96 170.18 90)
			(effects
				(font
					(size 1.27 1.27)
				)
				(justify right)
			)
		)
		(property "Value" "R_0R_0603"
			(at 325.12 153.67 0)
			(effects
				(font
					(size 1.27 1.27)
					(thickness 0.15)
				)
				(justify left bottom)
				(hide yes)
			)
		)
		(property "Footprint" "antmicro-footprints:R_0603_1608Metric"
			(at 327.66 153.67 0)
			(effects
				(font
					(size 1.27 1.27)
					(thickness 0.15)
				)
				(justify left bottom)
				(hide yes)
			)
		)
		(property "Datasheet" "https://www.bourns.com/docs/product-datasheets/cr.pdf?sfvrsn=574d41f6_14"
			(at 330.2 153.67 0)
			(effects
				(font
					(size 1.27 1.27)
					(thickness 0.15)
				)
				(justify left bottom)
				(hide yes)
			)
		)
		(property "Description" ""
			(at 312.42 173.99 0)
			(effects
				(font
					(size 1.27 1.27)
				)
				(hide yes)
			)
		)
		(property "Manufacturer" "Bourns"
			(at 335.28 153.67 0)
			(effects
				(font
					(size 1.27 1.27)
					(thickness 0.15)
				)
				(justify left bottom)
				(hide yes)
			)
		)
		(property "MPN" "CR0603-J/-000ELF"
			(at 332.74 153.67 0)
			(effects
				(font
					(size 1.27 1.27)
					(thickness 0.15)
				)
				(justify left bottom)
				(hide yes)
			)
		)
		(property "Val" "0R"
			(at 314.96 172.72 90)
			(effects
				(font
					(size 1.27 1.27)
					(thickness 0.15)
				)
				(justify right)
			)
		)
		(property "License" "Apache-2.0"
			(at 337.82 153.67 0)
			(effects
				(font
					(size 1.27 1.27)
					(thickness 0.15)
				)
				(justify left bottom)
				(hide yes)
			)
		)
		(property "Author" "Antmicro"
			(at 340.36 153.67 0)
			(effects
				(font
					(size 1.27 1.27)
					(thickness 0.15)
				)
				(justify left bottom)
				(hide yes)
			)
		)
		(property "Tolerance" "~"
			(at 322.58 153.67 0)
			(effects
				(font
					(size 1.27 1.27)
				)
				(justify left bottom)
				(hide yes)
			)
		)
		(property "Current" "1A"
			(at 342.9 153.67 0)
			(effects
				(font
					(size 1.27 1.27)
					(thickness 0.15)
				)
				(justify left bottom)
				(hide yes)
			)
		)
		(pin "1"
		)
		(pin "2"
		)
		(instances
			(project "jetson-orin-baseboard"
				(path ""
					(reference "R247")
					(unit 1)
				)
			)
		)
	)
	(symbol
		(lib_name "Tag-Connect_TC2050-IDC-NL_2x5_P1.27mm_1")
		(lib_id "antmicroTestPoints:Tag-Connect_TC2050-IDC-NL_2x5_P1.27mm")
		(at 45.72 232.41 0)
		(unit 1)
		(exclude_from_sim no)
		(in_bom no)
		(on_board yes)
		(dnp yes)
		(fields_autoplaced yes)
		(property "Reference" "J9"
			(at 60.325 224.79 0)
			(effects
				(font
					(size 1.27 1.27)
					(thickness 0.15)
				)
			)
		)
		(property "Value" "Tag-Connect_TC2050-IDC-NL_2x5_P1.27mm"
			(at 83.82 236.22 0)
			(effects
				(font
					(size 1.27 1.27)
					(thickness 0.15)
				)
				(justify left bottom)
				(hide yes)
			)
		)
		(property "Footprint" "antmicro-footprints:Tag-Connect_TC2050-IDC-NL_2x5_P1.27mm"
			(at 83.82 238.76 0)
			(effects
				(font
					(size 1.27 1.27)
					(thickness 0.15)
				)
				(justify left bottom)
				(hide yes)
			)
		)
		(property "Datasheet" "https://www.tag-connect.com/wp-content/uploads/bsk-pdf-manager/TC2050-IDC-NL_Datasheet_8.pdf"
			(at 83.82 241.3 0)
			(effects
				(font
					(size 1.27 1.27)
					(thickness 0.15)
				)
				(justify left bottom)
				(hide yes)
			)
		)
		(property "Description" ""
			(at 45.72 232.41 0)
			(effects
				(font
					(size 1.27 1.27)
				)
				(hide yes)
			)
		)
		(property "MPN" "TC2050-IDC-NL"
			(at 60.325 227.33 0)
			(effects
				(font
					(size 1.27 1.27)
					(thickness 0.15)
				)
			)
		)
		(property "Manufacturer" "Tag Connect"
			(at 83.82 246.38 0)
			(effects
				(font
					(size 1.27 1.27)
					(thickness 0.15)
				)
				(justify left bottom)
				(hide yes)
			)
		)
		(property "Author" "Antmicro"
			(at 83.82 248.92 0)
			(effects
				(font
					(size 1.27 1.27)
					(thickness 0.15)
				)
				(justify left bottom)
				(hide yes)
			)
		)
		(property "License" "Apache-2.0"
			(at 83.82 251.46 0)
			(effects
				(font
					(size 1.27 1.27)
					(thickness 0.15)
				)
				(justify left bottom)
				(hide yes)
			)
		)
		(pin "1"
			(alternate "3V3")
		)
		(pin "4"
			(alternate "SPI_SCK")
		)
		(pin "2"
			(alternate "SPI_CS")
		)
		(pin "3"
			(alternate "GND")
		)
		(pin "9"
			(alternate "GND")
		)
		(pin "10"
			(alternate "SPI_NC")
		)
		(pin "8"
			(alternate "SPI_MOSI")
		)
		(pin "5"
			(alternate "GND")
		)
		(pin "6"
			(alternate "SPI_MISO")
		)
		(pin "7"
			(alternate "NC")
		)
		(instances
			(project "jetson-orin-baseboard"
				(path ""
					(reference "J9")
					(unit 1)
				)
			)
		)
	)
	(symbol
		(lib_id "antmicroLEDIndicationDiscrete:LED_G_0603_LTST-C190GKT")
		(at 149.86 245.11 90)
		(unit 1)
		(exclude_from_sim no)
		(in_bom yes)
		(on_board yes)
		(dnp no)
		(property "Reference" "D26"
			(at 151.13 241.3 90)
			(effects
				(font
					(size 1.27 1.27)
				)
				(justify right)
			)
		)
		(property "Value" "LED_G_0603_LTST-C190GKT"
			(at 157.48 222.25 0)
			(effects
				(font
					(size 1.27 1.27)
					(thickness 0.15)
				)
				(justify left bottom)
				(hide yes)
			)
		)
		(property "Footprint" "antmicro-footprints:LED_0603_1608Metric_G"
			(at 160.02 222.25 0)
			(effects
				(font
					(size 1.27 1.27)
					(thickness 0.15)
				)
				(justify left bottom)
				(hide yes)
			)
		)
		(property "Datasheet" "https://media.digikey.com/pdf/Data%20Sheets/Lite-On%20PDFs/LTST-C190GKT.pdf"
			(at 162.56 222.25 0)
			(effects
				(font
					(size 1.27 1.27)
					(thickness 0.15)
				)
				(justify left bottom)
				(hide yes)
			)
		)
		(property "Description" ""
			(at 149.86 245.11 0)
			(effects
				(font
					(size 1.27 1.27)
				)
				(hide yes)
			)
		)
		(property "MPN" "LTST-C190GKT"
			(at 165.1 222.25 0)
			(effects
				(font
					(size 1.27 1.27)
					(thickness 0.15)
				)
				(justify left bottom)
				(hide yes)
			)
		)
		(property "Manufacturer" "Lite-On"
			(at 167.64 222.25 0)
			(effects
				(font
					(size 1.27 1.27)
					(thickness 0.15)
				)
				(justify left bottom)
				(hide yes)
			)
		)
		(property "Author" "Antmicro"
			(at 170.18 222.25 0)
			(effects
				(font
					(size 1.27 1.27)
					(thickness 0.15)
				)
				(justify left bottom)
				(hide yes)
			)
		)
		(property "License" "Apache-2.0"
			(at 172.72 222.25 0)
			(effects
				(font
					(size 1.27 1.27)
					(thickness 0.15)
				)
				(justify left bottom)
				(hide yes)
			)
		)
		(property "Color" "Green"
			(at 151.13 243.84 90)
			(effects
				(font
					(size 1.27 1.27)
				)
				(justify right)
			)
		)
		(pin "1"
		)
		(pin "2"
		)
		(instances
			(project "jetson-orin-baseboard"
				(path ""
					(reference "D26")
					(unit 1)
				)
			)
		)
	)
	(symbol
		(lib_id "antmicropower:+5V")
		(at 262.89 167.64 0)
		(unit 1)
		(exclude_from_sim no)
		(in_bom yes)
		(on_board yes)
		(dnp no)
		(property "Reference" "#PWR0238"
			(at 262.89 171.45 0)
			(effects
				(font
					(size 1.27 1.27)
				)
				(justify left bottom)
				(hide yes)
			)
		)
		(property "Value" "+5V"
			(at 262.89 163.83 0)
			(effects
				(font
					(size 1.27 1.27)
					(thickness 0.15)
				)
			)
		)
		(property "Footprint" ""
			(at 278.13 175.26 0)
			(effects
				(font
					(size 1.27 1.27)
					(thickness 0.15)
				)
				(justify left bottom)
				(hide yes)
			)
		)
		(property "Datasheet" ""
			(at 278.13 177.8 0)
			(effects
				(font
					(size 1.27 1.27)
					(thickness 0.15)
				)
				(justify left bottom)
				(hide yes)
			)
		)
		(property "Description" ""
			(at 262.89 167.64 0)
			(effects
				(font
					(size 1.27 1.27)
				)
				(hide yes)
			)
		)
		(property "Author" "Antmicro"
			(at 278.13 175.26 0)
			(effects
				(font
					(size 1.27 1.27)
					(thickness 0.15)
				)
				(justify left bottom)
				(hide yes)
			)
		)
		(property "License" "Apache-2.0"
			(at 278.13 177.8 0)
			(effects
				(font
					(size 1.27 1.27)
					(thickness 0.15)
				)
				(justify left bottom)
				(hide yes)
			)
		)
		(pin "1"
		)
		(instances
			(project "jetson-orin-baseboard"
				(path ""
					(reference "#PWR0238")
					(unit 1)
				)
			)
		)
	)
	(symbol
		(lib_id "antmicroTVSDiodes:TPD1E0B04_XDFN-2")
		(at 388.62 193.04 0)
		(unit 1)
		(exclude_from_sim no)
		(in_bom yes)
		(on_board yes)
		(dnp no)
		(property "Reference" "D44"
			(at 393.065 192.405 0)
			(effects
				(font
					(size 1.27 1.27)
				)
				(justify left bottom)
			)
		)
		(property "Value" "TPD1E0B04_XDFN-2"
			(at 403.86 203.2 0)
			(effects
				(font
					(size 1.27 1.27)
					(thickness 0.15)
				)
				(justify left bottom)
				(hide yes)
			)
		)
		(property "Footprint" "antmicro-footprints:XDFN-2_1x0.60mm"
			(at 403.86 198.12 0)
			(effects
				(font
					(size 1.27 1.27)
					(thickness 0.15)
				)
				(justify left bottom)
				(hide yes)
			)
		)
		(property "Datasheet" "https://www.ti.com/general/docs/suppproductinfo.tsp?distId=26&gotoUrl=https://www.ti.com/lit/gpn/tpd1e0b04"
			(at 403.86 200.66 0)
			(effects
				(font
					(size 1.27 1.27)
					(thickness 0.15)
				)
				(justify left bottom)
				(hide yes)
			)
		)
		(property "Description" ""
			(at 388.62 193.04 0)
			(effects
				(font
					(size 1.27 1.27)
				)
				(hide yes)
			)
		)
		(property "Manufacturer" "Texas Instruments"
			(at 403.86 205.74 0)
			(effects
				(font
					(size 1.27 1.27)
					(thickness 0.15)
				)
				(justify left bottom)
				(hide yes)
			)
		)
		(property "MPN" "TPD1E0B04DPYR"
			(at 373.38 192.405 0)
			(effects
				(font
					(size 1.27 1.27)
					(thickness 0.15)
				)
				(justify left bottom)
			)
		)
		(property "Author" "Antmicro"
			(at 403.86 208.28 0)
			(effects
				(font
					(size 1.27 1.27)
					(thickness 0.15)
				)
				(justify left bottom)
				(hide yes)
			)
		)
		(property "License" "Apache-2.0"
			(at 403.86 210.82 0)
			(effects
				(font
					(size 1.27 1.27)
					(thickness 0.15)
				)
				(justify left bottom)
				(hide yes)
			)
		)
		(pin "1"
		)
		(pin "2"
		)
		(instances
			(project "jetson-orin-baseboard"
				(path ""
					(reference "D44")
					(unit 1)
				)
			)
		)
	)
	(symbol
		(lib_id "antmicropower:VCC")
		(at 246.38 167.64 0)
		(unit 1)
		(exclude_from_sim no)
		(in_bom yes)
		(on_board yes)
		(dnp no)
		(property "Reference" "#PWR0322"
			(at 246.38 171.45 0)
			(effects
				(font
					(size 1.27 1.27)
				)
				(justify left bottom)
				(hide yes)
			)
		)
		(property "Value" "VCC"
			(at 244.475 163.83 0)
			(effects
				(font
					(size 1.27 1.27)
				)
				(justify left)
			)
		)
		(property "Footprint" ""
			(at 246.38 167.64 0)
			(effects
				(font
					(size 1.27 1.27)
				)
				(hide yes)
			)
		)
		(property "Datasheet" ""
			(at 246.38 167.64 0)
			(effects
				(font
					(size 1.27 1.27)
				)
				(hide yes)
			)
		)
		(property "Description" ""
			(at 246.38 167.64 0)
			(effects
				(font
					(size 1.27 1.27)
				)
				(hide yes)
			)
		)
		(pin "1"
		)
		(instances
			(project "jetson-orin-baseboard"
				(path ""
					(reference "#PWR0322")
					(unit 1)
				)
			)
		)
	)
	(symbol
		(lib_id "antmicropower:+3V3")
		(at 208.28 232.41 0)
		(unit 1)
		(exclude_from_sim no)
		(in_bom yes)
		(on_board yes)
		(dnp no)
		(property "Reference" "#PWR0232"
			(at 208.28 236.22 0)
			(effects
				(font
					(size 1.27 1.27)
				)
				(justify left bottom)
				(hide yes)
			)
		)
		(property "Value" "+3V3"
			(at 205.105 228.6 0)
			(effects
				(font
					(size 1.27 1.27)
					(thickness 0.15)
				)
				(justify left)
			)
		)
		(property "Footprint" ""
			(at 223.52 240.03 0)
			(effects
				(font
					(size 1.27 1.27)
					(thickness 0.15)
				)
				(justify left bottom)
				(hide yes)
			)
		)
		(property "Datasheet" ""
			(at 223.52 242.57 0)
			(effects
				(font
					(size 1.27 1.27)
					(thickness 0.15)
				)
				(justify left bottom)
				(hide yes)
			)
		)
		(property "Description" ""
			(at 208.28 232.41 0)
			(effects
				(font
					(size 1.27 1.27)
				)
				(hide yes)
			)
		)
		(property "Author" "Antmicro"
			(at 223.52 234.95 0)
			(effects
				(font
					(size 1.27 1.27)
					(thickness 0.15)
				)
				(justify left bottom)
				(hide yes)
			)
		)
		(property "License" "Apache-2.0"
			(at 223.52 237.49 0)
			(effects
				(font
					(size 1.27 1.27)
					(thickness 0.15)
				)
				(justify left bottom)
				(hide yes)
			)
		)
		(pin "1"
		)
		(instances
			(project "jetson-orin-baseboard"
				(path ""
					(reference "#PWR0232")
					(unit 1)
				)
			)
		)
	)
	(symbol
		(lib_id "antmicroCapacitors0402:C_100n_0402")
		(at 57.15 60.96 90)
		(unit 1)
		(exclude_from_sim no)
		(in_bom yes)
		(on_board yes)
		(dnp no)
		(property "Reference" "C104"
			(at 59.055 57.15 90)
			(effects
				(font
					(size 1.27 1.27)
				)
				(justify right)
			)
		)
		(property "Value" "C_100n_0402"
			(at 67.31 40.64 0)
			(effects
				(font
					(size 1.27 1.27)
					(thickness 0.15)
				)
				(justify left bottom)
				(hide yes)
			)
		)
		(property "Footprint" "antmicro-footprints:C_0402_1005Metric"
			(at 69.85 40.64 0)
			(effects
				(font
					(size 1.27 1.27)
					(thickness 0.15)
				)
				(justify left bottom)
				(hide yes)
			)
		)
		(property "Datasheet" "https://www.murata.com/products/productdetail?partno=GRM155R61H104KE14%23"
			(at 72.39 40.64 0)
			(effects
				(font
					(size 1.27 1.27)
					(thickness 0.15)
				)
				(justify left bottom)
				(hide yes)
			)
		)
		(property "Description" ""
			(at 57.15 60.96 0)
			(effects
				(font
					(size 1.27 1.27)
				)
				(hide yes)
			)
		)
		(property "Manufacturer" "Murata"
			(at 77.47 40.64 0)
			(effects
				(font
					(size 1.27 1.27)
					(thickness 0.15)
				)
				(justify left bottom)
				(hide yes)
			)
		)
		(property "MPN" "GRM155R61H104KE14D"
			(at 74.93 40.64 0)
			(effects
				(font
					(size 1.27 1.27)
					(thickness 0.15)
				)
				(justify left bottom)
				(hide yes)
			)
		)
		(property "Val" "100n"
			(at 59.055 59.69 90)
			(effects
				(font
					(size 1.27 1.27)
					(thickness 0.15)
				)
				(justify right)
			)
		)
		(property "License" "Apache-2.0"
			(at 80.01 40.64 0)
			(effects
				(font
					(size 1.27 1.27)
					(thickness 0.15)
				)
				(justify left bottom)
				(hide yes)
			)
		)
		(property "Author" "Antmicro"
			(at 82.55 40.64 0)
			(effects
				(font
					(size 1.27 1.27)
					(thickness 0.15)
				)
				(justify left bottom)
				(hide yes)
			)
		)
		(property "Voltage" "50V"
			(at 85.09 40.64 0)
			(effects
				(font
					(size 1.27 1.27)
				)
				(justify left bottom)
				(hide yes)
			)
		)
		(property "Dielectric" "X5R"
			(at 87.63 40.64 0)
			(effects
				(font
					(size 1.27 1.27)
				)
				(justify left bottom)
				(hide yes)
			)
		)
		(pin "1"
		)
		(pin "2"
		)
		(instances
			(project "jetson-orin-baseboard"
				(path ""
					(reference "C104")
					(unit 1)
				)
			)
		)
	)
	(symbol
		(lib_id "antmicroTVSDiodes:TPD1E0B04_XDFN-2")
		(at 388.62 198.12 0)
		(unit 1)
		(exclude_from_sim no)
		(in_bom yes)
		(on_board yes)
		(dnp no)
		(property "Reference" "D45"
			(at 393.065 197.485 0)
			(effects
				(font
					(size 1.27 1.27)
				)
				(justify left bottom)
			)
		)
		(property "Value" "TPD1E0B04_XDFN-2"
			(at 403.86 208.28 0)
			(effects
				(font
					(size 1.27 1.27)
					(thickness 0.15)
				)
				(justify left bottom)
				(hide yes)
			)
		)
		(property "Footprint" "antmicro-footprints:XDFN-2_1x0.60mm"
			(at 403.86 203.2 0)
			(effects
				(font
					(size 1.27 1.27)
					(thickness 0.15)
				)
				(justify left bottom)
				(hide yes)
			)
		)
		(property "Datasheet" "https://www.ti.com/general/docs/suppproductinfo.tsp?distId=26&gotoUrl=https://www.ti.com/lit/gpn/tpd1e0b04"
			(at 403.86 205.74 0)
			(effects
				(font
					(size 1.27 1.27)
					(thickness 0.15)
				)
				(justify left bottom)
				(hide yes)
			)
		)
		(property "Description" ""
			(at 388.62 198.12 0)
			(effects
				(font
					(size 1.27 1.27)
				)
				(hide yes)
			)
		)
		(property "Manufacturer" "Texas Instruments"
			(at 403.86 210.82 0)
			(effects
				(font
					(size 1.27 1.27)
					(thickness 0.15)
				)
				(justify left bottom)
				(hide yes)
			)
		)
		(property "MPN" "TPD1E0B04DPYR"
			(at 373.38 197.485 0)
			(effects
				(font
					(size 1.27 1.27)
					(thickness 0.15)
				)
				(justify left bottom)
			)
		)
		(property "Author" "Antmicro"
			(at 403.86 213.36 0)
			(effects
				(font
					(size 1.27 1.27)
					(thickness 0.15)
				)
				(justify left bottom)
				(hide yes)
			)
		)
		(property "License" "Apache-2.0"
			(at 403.86 215.9 0)
			(effects
				(font
					(size 1.27 1.27)
					(thickness 0.15)
				)
				(justify left bottom)
				(hide yes)
			)
		)
		(pin "1"
		)
		(pin "2"
		)
		(instances
			(project "jetson-orin-baseboard"
				(path ""
					(reference "D45")
					(unit 1)
				)
			)
		)
	)
	(symbol
		(lib_id "antmicropower:GND")
		(at 279.4 186.69 0)
		(unit 1)
		(exclude_from_sim no)
		(in_bom yes)
		(on_board yes)
		(dnp no)
		(fields_autoplaced yes)
		(property "Reference" "#PWR0242"
			(at 279.4 193.04 0)
			(effects
				(font
					(size 1.27 1.27)
				)
				(justify left bottom)
				(hide yes)
			)
		)
		(property "Value" "GND"
			(at 279.4 190.5 0)
			(effects
				(font
					(size 1.27 1.27)
					(thickness 0.15)
				)
			)
		)
		(property "Footprint" ""
			(at 288.29 194.31 0)
			(effects
				(font
					(size 1.27 1.27)
					(thickness 0.15)
				)
				(justify left bottom)
				(hide yes)
			)
		)
		(property "Datasheet" ""
			(at 288.29 199.39 0)
			(effects
				(font
					(size 1.27 1.27)
					(thickness 0.15)
				)
				(justify left bottom)
				(hide yes)
			)
		)
		(property "Description" ""
			(at 279.4 186.69 0)
			(effects
				(font
					(size 1.27 1.27)
				)
				(hide yes)
			)
		)
		(property "Author" "Antmicro"
			(at 288.29 194.31 0)
			(effects
				(font
					(size 1.27 1.27)
					(thickness 0.15)
				)
				(justify left bottom)
				(hide yes)
			)
		)
		(property "License" "Apache-2.0"
			(at 288.29 196.85 0)
			(effects
				(font
					(size 1.27 1.27)
					(thickness 0.15)
				)
				(justify left bottom)
				(hide yes)
			)
		)
		(pin "1"
		)
		(instances
			(project "jetson-orin-baseboard"
				(path ""
					(reference "#PWR0242")
					(unit 1)
				)
			)
		)
	)
	(symbol
		(lib_id "antmicroResistorNetworksArrays:R_4x0R_0201_array")
		(at 113.03 60.96 0)
		(mirror y)
		(unit 1)
		(exclude_from_sim no)
		(in_bom yes)
		(on_board yes)
		(dnp no)
		(property "Reference" "R25"
			(at 107.95 55.245 0)
			(effects
				(font
					(size 1.27 1.27)
				)
			)
		)
		(property "Value" "R_4x0R_0201_array"
			(at 86.36 68.58 0)
			(effects
				(font
					(size 1.27 1.27)
					(thickness 0.15)
				)
				(justify left bottom)
				(hide yes)
			)
		)
		(property "Footprint" "antmicro-footprints:R_Array_4x0201_Panasonic_EXB18V"
			(at 86.36 73.66 0)
			(effects
				(font
					(size 1.27 1.27)
					(thickness 0.15)
				)
				(justify left bottom)
				(hide yes)
			)
		)
		(property "Datasheet" "http://industrial.panasonic.com/cdbs/www-data/pdf/AOC0000/AOC0000C14.pdf"
			(at 86.36 76.2 0)
			(effects
				(font
					(size 1.27 1.27)
					(thickness 0.15)
				)
				(justify left bottom)
				(hide yes)
			)
		)
		(property "Description" ""
			(at 113.03 60.96 0)
			(effects
				(font
					(size 1.27 1.27)
				)
				(hide yes)
			)
		)
		(property "MPN" "EXB-18VR000X"
			(at 86.36 78.74 0)
			(effects
				(font
					(size 1.27 1.27)
					(thickness 0.15)
				)
				(justify left bottom)
				(hide yes)
			)
		)
		(property "Manufacturer" "Panasonic"
			(at 86.36 81.28 0)
			(effects
				(font
					(size 1.27 1.27)
					(thickness 0.15)
				)
				(justify left bottom)
				(hide yes)
			)
		)
		(property "Val" "4x0R_0201"
			(at 107.95 57.785 0)
			(effects
				(font
					(size 1.27 1.27)
					(thickness 0.15)
				)
			)
		)
		(property "Author" "Antmicro"
			(at 86.36 83.82 0)
			(effects
				(font
					(size 1.27 1.27)
					(thickness 0.15)
				)
				(justify left bottom)
				(hide yes)
			)
		)
		(property "License" "Apache-2.0"
			(at 86.36 86.36 0)
			(effects
				(font
					(size 1.27 1.27)
					(thickness 0.15)
				)
				(justify left bottom)
				(hide yes)
			)
		)
		(pin "1"
		)
		(pin "2"
		)
		(pin "3"
		)
		(pin "4"
		)
		(pin "5"
		)
		(pin "6"
		)
		(pin "7"
		)
		(pin "8"
		)
		(instances
			(project "jetson-orin-baseboard"
				(path ""
					(reference "R25")
					(unit 1)
				)
			)
		)
	)
	(symbol
		(lib_id "antmicroCapacitors0402:C_220n_0402")
		(at 281.94 45.72 180)
		(unit 1)
		(exclude_from_sim no)
		(in_bom yes)
		(on_board yes)
		(dnp no)
		(property "Reference" "C108"
			(at 280.67 45.085 0)
			(effects
				(font
					(size 1.27 1.27)
				)
				(justify right top)
			)
		)
		(property "Value" "C_220n_0402"
			(at 261.62 35.56 0)
			(effects
				(font
					(size 1.27 1.27)
					(thickness 0.15)
				)
				(justify left bottom)
				(hide yes)
			)
		)
		(property "Footprint" "antmicro-footprints:C_0402_1005Metric"
			(at 261.62 33.02 0)
			(effects
				(font
					(size 1.27 1.27)
					(thickness 0.15)
				)
				(justify left bottom)
				(hide yes)
			)
		)
		(property "Datasheet" "https://www.yageo.com/en/Chart/Download/pdf/CC0402KRX5R6BB224"
			(at 261.62 30.48 0)
			(effects
				(font
					(size 1.27 1.27)
					(thickness 0.15)
				)
				(justify left bottom)
				(hide yes)
			)
		)
		(property "Description" ""
			(at 281.94 45.72 0)
			(effects
				(font
					(size 1.27 1.27)
				)
				(hide yes)
			)
		)
		(property "Manufacturer" "YAGEO"
			(at 261.62 25.4 0)
			(effects
				(font
					(size 1.27 1.27)
					(thickness 0.15)
				)
				(justify left bottom)
				(hide yes)
			)
		)
		(property "MPN" "CC0402KRX5R6BB224"
			(at 261.62 27.94 0)
			(effects
				(font
					(size 1.27 1.27)
					(thickness 0.15)
				)
				(justify left bottom)
				(hide yes)
			)
		)
		(property "Val" "220n"
			(at 278.13 46.355 0)
			(effects
				(font
					(size 1.27 1.27)
					(thickness 0.15)
				)
				(justify left bottom)
			)
		)
		(property "License" "Apache-2.0"
			(at 261.62 22.86 0)
			(effects
				(font
					(size 1.27 1.27)
					(thickness 0.15)
				)
				(justify left bottom)
				(hide yes)
			)
		)
		(property "Author" "Antmicro"
			(at 261.62 20.32 0)
			(effects
				(font
					(size 1.27 1.27)
					(thickness 0.15)
				)
				(justify left bottom)
				(hide yes)
			)
		)
		(property "Voltage" ""
			(at 261.62 17.78 0)
			(effects
				(font
					(size 1.27 1.27)
				)
				(justify left bottom)
				(hide yes)
			)
		)
		(property "Dielectric" ""
			(at 261.62 15.24 0)
			(effects
				(font
					(size 1.27 1.27)
				)
				(justify left bottom)
				(hide yes)
			)
		)
		(pin "1"
		)
		(pin "2"
		)
		(instances
			(project "jetson-orin-baseboard"
				(path ""
					(reference "C108")
					(unit 1)
				)
			)
		)
	)
	(symbol
		(lib_id "antmicroResistors0402:R_200R_0402")
		(at 204.47 54.61 270)
		(mirror x)
		(unit 1)
		(exclude_from_sim no)
		(in_bom yes)
		(on_board yes)
		(dnp no)
		(property "Reference" "R191"
			(at 205.74 50.8 90)
			(effects
				(font
					(size 1.27 1.27)
				)
				(justify left)
			)
		)
		(property "Value" "R_200R_0402"
			(at 191.77 34.29 0)
			(effects
				(font
					(size 1.27 1.27)
					(thickness 0.15)
				)
				(justify left bottom)
				(hide yes)
			)
		)
		(property "Footprint" "antmicro-footprints:R_0402_1005Metric"
			(at 189.23 34.29 0)
			(effects
				(font
					(size 1.27 1.27)
					(thickness 0.15)
				)
				(justify left bottom)
				(hide yes)
			)
		)
		(property "Datasheet" "https://www.bourns.com/docs/product-datasheets/cr.pdf"
			(at 186.69 34.29 0)
			(effects
				(font
					(size 1.27 1.27)
					(thickness 0.15)
				)
				(justify left bottom)
				(hide yes)
			)
		)
		(property "Description" ""
			(at 204.47 54.61 0)
			(effects
				(font
					(size 1.27 1.27)
				)
				(hide yes)
			)
		)
		(property "Manufacturer" "Bourns"
			(at 181.61 34.29 0)
			(effects
				(font
					(size 1.27 1.27)
					(thickness 0.15)
				)
				(justify left bottom)
				(hide yes)
			)
		)
		(property "MPN" "CR0402-FX-2000GLF"
			(at 184.15 34.29 0)
			(effects
				(font
					(size 1.27 1.27)
					(thickness 0.15)
				)
				(justify left bottom)
				(hide yes)
			)
		)
		(property "Val" "200R"
			(at 205.74 53.34 90)
			(effects
				(font
					(size 1.27 1.27)
					(thickness 0.15)
				)
				(justify left)
			)
		)
		(property "License" "Apache-2.0"
			(at 179.07 34.29 0)
			(effects
				(font
					(size 1.27 1.27)
					(thickness 0.15)
				)
				(justify left bottom)
				(hide yes)
			)
		)
		(property "Author" "Antmicro"
			(at 176.53 34.29 0)
			(effects
				(font
					(size 1.27 1.27)
					(thickness 0.15)
				)
				(justify left bottom)
				(hide yes)
			)
		)
		(property "Tolerance" "1%"
			(at 194.31 34.29 0)
			(effects
				(font
					(size 1.27 1.27)
				)
				(justify left bottom)
				(hide yes)
			)
		)
		(pin "1"
		)
		(pin "2"
		)
		(instances
			(project "jetson-orin-baseboard"
				(path ""
					(reference "R191")
					(unit 1)
				)
			)
		)
	)
	(symbol
		(lib_id "antmicroResistors0402:R_10k_0402")
		(at 261.62 231.14 90)
		(unit 1)
		(exclude_from_sim no)
		(in_bom yes)
		(on_board yes)
		(dnp no)
		(property "Reference" "R232"
			(at 262.89 227.33 90)
			(effects
				(font
					(size 1.27 1.27)
				)
				(justify right)
			)
		)
		(property "Value" "R_10k_0402"
			(at 274.32 210.82 0)
			(effects
				(font
					(size 1.27 1.27)
					(thickness 0.15)
				)
				(justify left bottom)
				(hide yes)
			)
		)
		(property "Footprint" "antmicro-footprints:R_0402_1005Metric"
			(at 276.86 210.82 0)
			(effects
				(font
					(size 1.27 1.27)
					(thickness 0.15)
				)
				(justify left bottom)
				(hide yes)
			)
		)
		(property "Datasheet" "https://www.bourns.com/docs/product-datasheets/cr.pdf"
			(at 279.4 210.82 0)
			(effects
				(font
					(size 1.27 1.27)
					(thickness 0.15)
				)
				(justify left bottom)
				(hide yes)
			)
		)
		(property "Description" ""
			(at 261.62 231.14 0)
			(effects
				(font
					(size 1.27 1.27)
				)
				(hide yes)
			)
		)
		(property "Manufacturer" "Bourns"
			(at 284.48 210.82 0)
			(effects
				(font
					(size 1.27 1.27)
					(thickness 0.15)
				)
				(justify left bottom)
				(hide yes)
			)
		)
		(property "MPN" "CR0402-FX-1002GLF"
			(at 281.94 210.82 0)
			(effects
				(font
					(size 1.27 1.27)
					(thickness 0.15)
				)
				(justify left bottom)
				(hide yes)
			)
		)
		(property "Val" "10k"
			(at 262.89 229.87 90)
			(effects
				(font
					(size 1.27 1.27)
					(thickness 0.15)
				)
				(justify right)
			)
		)
		(property "License" "Apache-2.0"
			(at 287.02 210.82 0)
			(effects
				(font
					(size 1.27 1.27)
					(thickness 0.15)
				)
				(justify left bottom)
				(hide yes)
			)
		)
		(property "Author" "Antmicro"
			(at 289.56 210.82 0)
			(effects
				(font
					(size 1.27 1.27)
					(thickness 0.15)
				)
				(justify left bottom)
				(hide yes)
			)
		)
		(property "Tolerance" "1%"
			(at 271.78 210.82 0)
			(effects
				(font
					(size 1.27 1.27)
				)
				(justify left bottom)
				(hide yes)
			)
		)
		(pin "1"
		)
		(pin "2"
		)
		(instances
			(project "jetson-orin-baseboard"
				(path ""
					(reference "R232")
					(unit 1)
				)
			)
		)
	)
	(symbol
		(lib_id "antmicroResistors0402:R_0R_0402")
		(at 303.53 116.84 0)
		(unit 1)
		(exclude_from_sim no)
		(in_bom yes)
		(on_board yes)
		(dnp no)
		(property "Reference" "R62"
			(at 308.61 116.205 0)
			(effects
				(font
					(size 1.27 1.27)
				)
				(justify left bottom)
			)
		)
		(property "Value" "R_0R_0402"
			(at 323.85 129.54 0)
			(effects
				(font
					(size 1.27 1.27)
					(thickness 0.15)
				)
				(justify left bottom)
				(hide yes)
			)
		)
		(property "Footprint" "antmicro-footprints:R_0402_1005Metric"
			(at 323.85 132.08 0)
			(effects
				(font
					(size 1.27 1.27)
					(thickness 0.15)
				)
				(justify left bottom)
				(hide yes)
			)
		)
		(property "Datasheet" "https://industrial.panasonic.com/cdbs/www-data/pdf/RDA0000/AOA0000C301.pdf"
			(at 323.85 134.62 0)
			(effects
				(font
					(size 1.27 1.27)
					(thickness 0.15)
				)
				(justify left bottom)
				(hide yes)
			)
		)
		(property "Description" ""
			(at 303.53 116.84 0)
			(effects
				(font
					(size 1.27 1.27)
				)
				(hide yes)
			)
		)
		(property "Manufacturer" "Panasonic"
			(at 323.85 139.7 0)
			(effects
				(font
					(size 1.27 1.27)
					(thickness 0.15)
				)
				(justify left bottom)
				(hide yes)
			)
		)
		(property "MPN" "ERJ2GE0R00X"
			(at 323.85 137.16 0)
			(effects
				(font
					(size 1.27 1.27)
					(thickness 0.15)
				)
				(justify left bottom)
				(hide yes)
			)
		)
		(property "Val" "0R"
			(at 300.99 116.205 0)
			(effects
				(font
					(size 1.27 1.27)
					(thickness 0.15)
				)
				(justify left bottom)
			)
		)
		(property "License" "Apache-2.0"
			(at 323.85 142.24 0)
			(effects
				(font
					(size 1.27 1.27)
					(thickness 0.15)
				)
				(justify left bottom)
				(hide yes)
			)
		)
		(property "Author" "Antmicro"
			(at 323.85 144.78 0)
			(effects
				(font
					(size 1.27 1.27)
					(thickness 0.15)
				)
				(justify left bottom)
				(hide yes)
			)
		)
		(property "Tolerance" "~"
			(at 323.85 127 0)
			(effects
				(font
					(size 1.27 1.27)
				)
				(justify left bottom)
				(hide yes)
			)
		)
		(property "Current" "1A"
			(at 323.85 147.32 0)
			(effects
				(font
					(size 1.27 1.27)
					(thickness 0.15)
				)
				(justify left bottom)
				(hide yes)
			)
		)
		(pin "1"
		)
		(pin "2"
		)
		(instances
			(project "jetson-orin-baseboard"
				(path ""
					(reference "R62")
					(unit 1)
				)
			)
		)
	)
	(symbol
		(lib_id "antmicroResistors0402:R_0R_0402")
		(at 284.48 88.9 180)
		(unit 1)
		(exclude_from_sim no)
		(in_bom no)
		(on_board yes)
		(dnp yes)
		(property "Reference" "R141"
			(at 284.48 88.265 0)
			(effects
				(font
					(size 1.27 1.27)
				)
				(justify right top)
			)
		)
		(property "Value" "R_0R_0402"
			(at 264.16 76.2 0)
			(effects
				(font
					(size 1.27 1.27)
					(thickness 0.15)
				)
				(justify left bottom)
				(hide yes)
			)
		)
		(property "Footprint" "antmicro-footprints:R_0402_1005Metric"
			(at 264.16 73.66 0)
			(effects
				(font
					(size 1.27 1.27)
					(thickness 0.15)
				)
				(justify left bottom)
				(hide yes)
			)
		)
		(property "Datasheet" "https://industrial.panasonic.com/cdbs/www-data/pdf/RDA0000/AOA0000C301.pdf"
			(at 264.16 71.12 0)
			(effects
				(font
					(size 1.27 1.27)
					(thickness 0.15)
				)
				(justify left bottom)
				(hide yes)
			)
		)
		(property "Description" ""
			(at 284.48 88.9 0)
			(effects
				(font
					(size 1.27 1.27)
				)
				(hide yes)
			)
		)
		(property "Manufacturer" "Panasonic"
			(at 264.16 66.04 0)
			(effects
				(font
					(size 1.27 1.27)
					(thickness 0.15)
				)
				(justify left bottom)
				(hide yes)
			)
		)
		(property "MPN" "ERJ2GE0R00X"
			(at 264.16 68.58 0)
			(effects
				(font
					(size 1.27 1.27)
					(thickness 0.15)
				)
				(justify left bottom)
				(hide yes)
			)
		)
		(property "Val" "0R"
			(at 276.86 88.265 0)
			(effects
				(font
					(size 1.27 1.27)
					(thickness 0.15)
				)
				(justify right top)
			)
		)
		(property "License" "Apache-2.0"
			(at 264.16 63.5 0)
			(effects
				(font
					(size 1.27 1.27)
					(thickness 0.15)
				)
				(justify left bottom)
				(hide yes)
			)
		)
		(property "Author" "Antmicro"
			(at 264.16 60.96 0)
			(effects
				(font
					(size 1.27 1.27)
					(thickness 0.15)
				)
				(justify left bottom)
				(hide yes)
			)
		)
		(property "Tolerance" "~"
			(at 264.16 78.74 0)
			(effects
				(font
					(size 1.27 1.27)
				)
				(justify left bottom)
				(hide yes)
			)
		)
		(property "Current" "1A"
			(at 264.16 58.42 0)
			(effects
				(font
					(size 1.27 1.27)
					(thickness 0.15)
				)
				(justify left bottom)
				(hide yes)
			)
		)
		(pin "1"
		)
		(pin "2"
		)
		(instances
			(project "jetson-orin-baseboard"
				(path ""
					(reference "R141")
					(unit 1)
				)
			)
		)
	)
	(symbol
		(lib_id "antmicropower:GND")
		(at 140.97 261.62 0)
		(unit 1)
		(exclude_from_sim no)
		(in_bom yes)
		(on_board yes)
		(dnp no)
		(fields_autoplaced yes)
		(property "Reference" "#PWR0235"
			(at 140.97 267.97 0)
			(effects
				(font
					(size 1.27 1.27)
				)
				(justify left bottom)
				(hide yes)
			)
		)
		(property "Value" "GND"
			(at 140.97 265.43 0)
			(effects
				(font
					(size 1.27 1.27)
					(thickness 0.15)
				)
			)
		)
		(property "Footprint" ""
			(at 149.86 269.24 0)
			(effects
				(font
					(size 1.27 1.27)
					(thickness 0.15)
				)
				(justify left bottom)
				(hide yes)
			)
		)
		(property "Datasheet" ""
			(at 149.86 274.32 0)
			(effects
				(font
					(size 1.27 1.27)
					(thickness 0.15)
				)
				(justify left bottom)
				(hide yes)
			)
		)
		(property "Description" ""
			(at 140.97 261.62 0)
			(effects
				(font
					(size 1.27 1.27)
				)
				(hide yes)
			)
		)
		(property "Author" "Antmicro"
			(at 149.86 269.24 0)
			(effects
				(font
					(size 1.27 1.27)
					(thickness 0.15)
				)
				(justify left bottom)
				(hide yes)
			)
		)
		(property "License" "Apache-2.0"
			(at 149.86 271.78 0)
			(effects
				(font
					(size 1.27 1.27)
					(thickness 0.15)
				)
				(justify left bottom)
				(hide yes)
			)
		)
		(pin "1"
		)
		(instances
			(project "jetson-orin-baseboard"
				(path ""
					(reference "#PWR0235")
					(unit 1)
				)
			)
		)
	)
	(symbol
		(lib_id "antmicroLogicTranslatorsLevelShifters:NTS0102_XSON")
		(at 35.56 163.83 0)
		(unit 1)
		(exclude_from_sim no)
		(in_bom yes)
		(on_board yes)
		(dnp no)
		(property "Reference" "U33"
			(at 45.72 157.48 0)
			(effects
				(font
					(size 1.27 1.27)
				)
			)
		)
		(property "Value" "NTS0102_XSON"
			(at 71.12 171.45 0)
			(effects
				(font
					(size 1.27 1.27)
					(thickness 0.15)
				)
				(justify left bottom)
				(hide yes)
			)
		)
		(property "Footprint" "antmicro-footprints:XSON-8_1x1.95mm_P0.5mm"
			(at 71.12 173.99 0)
			(effects
				(font
					(size 1.27 1.27)
					(thickness 0.15)
				)
				(justify left bottom)
				(hide yes)
			)
		)
		(property "Datasheet" "http://www.farnell.com/datasheets/1760723.pdf"
			(at 71.12 176.53 0)
			(effects
				(font
					(size 1.27 1.27)
					(thickness 0.15)
				)
				(justify left bottom)
				(hide yes)
			)
		)
		(property "Description" ""
			(at 35.56 163.83 0)
			(effects
				(font
					(size 1.27 1.27)
				)
				(hide yes)
			)
		)
		(property "MPN" "NTS0102GT"
			(at 45.72 160.02 0)
			(effects
				(font
					(size 1.27 1.27)
					(thickness 0.15)
				)
			)
		)
		(property "Manufacturer" "NXP"
			(at 71.12 179.07 0)
			(effects
				(font
					(size 1.27 1.27)
					(thickness 0.15)
				)
				(justify left bottom)
				(hide yes)
			)
		)
		(property "Author" "Antmicro"
			(at 71.12 181.61 0)
			(effects
				(font
					(size 1.27 1.27)
					(thickness 0.15)
				)
				(justify left bottom)
				(hide yes)
			)
		)
		(property "License" "Apache-2.0"
			(at 71.12 184.15 0)
			(effects
				(font
					(size 1.27 1.27)
					(thickness 0.15)
				)
				(justify left bottom)
				(hide yes)
			)
		)
		(pin "1"
		)
		(pin "2"
		)
		(pin "3"
		)
		(pin "4"
		)
		(pin "5"
		)
		(pin "6"
		)
		(pin "7"
		)
		(pin "8"
		)
		(instances
			(project "jetson-orin-baseboard"
				(path ""
					(reference "U33")
					(unit 1)
				)
			)
		)
	)
	(symbol
		(lib_id "antmicroResistorNetworksArrays:R_4x100R_0201_array")
		(at 78.74 257.81 0)
		(unit 1)
		(exclude_from_sim no)
		(in_bom no)
		(on_board yes)
		(dnp yes)
		(property "Reference" "R112"
			(at 83.82 252.73 0)
			(effects
				(font
					(size 1.27 1.27)
					(thickness 0.15)
				)
			)
		)
		(property "Value" "R_4x100R_0201_array"
			(at 105.41 265.43 0)
			(effects
				(font
					(size 1.27 1.27)
					(thickness 0.15)
				)
				(justify left bottom)
				(hide yes)
			)
		)
		(property "Footprint" "antmicro-footprints:R_Array_4x0201_Panasonic_EXB18V"
			(at 105.41 270.51 0)
			(effects
				(font
					(size 1.27 1.27)
					(thickness 0.15)
				)
				(justify left bottom)
				(hide yes)
			)
		)
		(property "Datasheet" "http://industrial.panasonic.com/cdbs/www-data/pdf/AOC0000/AOC0000C14.pdf"
			(at 105.41 273.05 0)
			(effects
				(font
					(size 1.27 1.27)
					(thickness 0.15)
				)
				(justify left bottom)
				(hide yes)
			)
		)
		(property "Description" ""
			(at 78.74 257.81 0)
			(effects
				(font
					(size 1.27 1.27)
				)
				(hide yes)
			)
		)
		(property "MPN" "EXB-18V101JX"
			(at 105.41 275.59 0)
			(effects
				(font
					(size 1.27 1.27)
					(thickness 0.15)
				)
				(justify left bottom)
				(hide yes)
			)
		)
		(property "Manufacturer" "Panasonic"
			(at 105.41 278.13 0)
			(effects
				(font
					(size 1.27 1.27)
					(thickness 0.15)
				)
				(justify left bottom)
				(hide yes)
			)
		)
		(property "Val" "R_4x100R_0201"
			(at 83.82 255.27 0)
			(effects
				(font
					(size 1.27 1.27)
					(thickness 0.15)
				)
			)
		)
		(property "Author" "Antmicro"
			(at 105.41 280.67 0)
			(effects
				(font
					(size 1.27 1.27)
					(thickness 0.15)
				)
				(justify left bottom)
				(hide yes)
			)
		)
		(property "License" "Apache-2.0"
			(at 105.41 283.21 0)
			(effects
				(font
					(size 1.27 1.27)
					(thickness 0.15)
				)
				(justify left bottom)
				(hide yes)
			)
		)
		(pin "6"
		)
		(pin "5"
		)
		(pin "4"
		)
		(pin "3"
		)
		(pin "2"
		)
		(pin "7"
		)
		(pin "1"
		)
		(pin "8"
		)
		(instances
			(project "jetson-orin-baseboard"
				(path ""
					(reference "R112")
					(unit 1)
				)
			)
		)
	)
	(symbol
		(lib_id "antmicroLEDIndicationDiscrete:LED_G_0603_LTST-C190GKT")
		(at 204.47 60.96 270)
		(mirror x)
		(unit 1)
		(exclude_from_sim no)
		(in_bom yes)
		(on_board yes)
		(dnp no)
		(property "Reference" "D54"
			(at 207.645 57.15 90)
			(effects
				(font
					(size 1.27 1.27)
				)
				(justify left)
			)
		)
		(property "Value" "LED_G_0603_LTST-C190GKT"
			(at 196.85 38.1 0)
			(effects
				(font
					(size 1.27 1.27)
					(thickness 0.15)
				)
				(justify left bottom)
				(hide yes)
			)
		)
		(property "Footprint" "antmicro-footprints:LED_0603_1608Metric_G"
			(at 194.31 38.1 0)
			(effects
				(font
					(size 1.27 1.27)
					(thickness 0.15)
				)
				(justify left bottom)
				(hide yes)
			)
		)
		(property "Datasheet" "https://media.digikey.com/pdf/Data%20Sheets/Lite-On%20PDFs/LTST-C190GKT.pdf"
			(at 191.77 38.1 0)
			(effects
				(font
					(size 1.27 1.27)
					(thickness 0.15)
				)
				(justify left bottom)
				(hide yes)
			)
		)
		(property "Description" ""
			(at 204.47 60.96 0)
			(effects
				(font
					(size 1.27 1.27)
				)
				(hide yes)
			)
		)
		(property "MPN" "LTST-C190GKT"
			(at 189.23 38.1 0)
			(effects
				(font
					(size 1.27 1.27)
					(thickness 0.15)
				)
				(justify left bottom)
				(hide yes)
			)
		)
		(property "Manufacturer" "Lite-On"
			(at 186.69 38.1 0)
			(effects
				(font
					(size 1.27 1.27)
					(thickness 0.15)
				)
				(justify left bottom)
				(hide yes)
			)
		)
		(property "Author" "Antmicro"
			(at 184.15 38.1 0)
			(effects
				(font
					(size 1.27 1.27)
					(thickness 0.15)
				)
				(justify left bottom)
				(hide yes)
			)
		)
		(property "License" "Apache-2.0"
			(at 181.61 38.1 0)
			(effects
				(font
					(size 1.27 1.27)
					(thickness 0.15)
				)
				(justify left bottom)
				(hide yes)
			)
		)
		(property "Color" "Green"
			(at 207.645 59.69 90)
			(effects
				(font
					(size 1.27 1.27)
				)
				(justify left)
			)
		)
		(pin "1"
		)
		(pin "2"
		)
		(instances
			(project "jetson-orin-baseboard"
				(path ""
					(reference "D54")
					(unit 1)
				)
			)
		)
	)
	(symbol
		(lib_id "antmicroResistors0402:R_10k_0402")
		(at 44.45 60.96 90)
		(unit 1)
		(exclude_from_sim no)
		(in_bom yes)
		(on_board yes)
		(dnp no)
		(property "Reference" "R219"
			(at 45.72 57.15 90)
			(effects
				(font
					(size 1.27 1.27)
				)
				(justify right)
			)
		)
		(property "Value" "R_10k_0402"
			(at 57.15 40.64 0)
			(effects
				(font
					(size 1.27 1.27)
					(thickness 0.15)
				)
				(justify left bottom)
				(hide yes)
			)
		)
		(property "Footprint" "antmicro-footprints:R_0402_1005Metric"
			(at 59.69 40.64 0)
			(effects
				(font
					(size 1.27 1.27)
					(thickness 0.15)
				)
				(justify left bottom)
				(hide yes)
			)
		)
		(property "Datasheet" "https://www.bourns.com/docs/product-datasheets/cr.pdf"
			(at 62.23 40.64 0)
			(effects
				(font
					(size 1.27 1.27)
					(thickness 0.15)
				)
				(justify left bottom)
				(hide yes)
			)
		)
		(property "Description" ""
			(at 44.45 60.96 0)
			(effects
				(font
					(size 1.27 1.27)
				)
				(hide yes)
			)
		)
		(property "Manufacturer" "Bourns"
			(at 67.31 40.64 0)
			(effects
				(font
					(size 1.27 1.27)
					(thickness 0.15)
				)
				(justify left bottom)
				(hide yes)
			)
		)
		(property "MPN" "CR0402-FX-1002GLF"
			(at 64.77 40.64 0)
			(effects
				(font
					(size 1.27 1.27)
					(thickness 0.15)
				)
				(justify left bottom)
				(hide yes)
			)
		)
		(property "Val" "10k"
			(at 45.72 59.69 90)
			(effects
				(font
					(size 1.27 1.27)
					(thickness 0.15)
				)
				(justify right)
			)
		)
		(property "License" "Apache-2.0"
			(at 69.85 40.64 0)
			(effects
				(font
					(size 1.27 1.27)
					(thickness 0.15)
				)
				(justify left bottom)
				(hide yes)
			)
		)
		(property "Author" "Antmicro"
			(at 72.39 40.64 0)
			(effects
				(font
					(size 1.27 1.27)
					(thickness 0.15)
				)
				(justify left bottom)
				(hide yes)
			)
		)
		(property "Tolerance" "1%"
			(at 54.61 40.64 0)
			(effects
				(font
					(size 1.27 1.27)
				)
				(justify left bottom)
				(hide yes)
			)
		)
		(pin "1"
		)
		(pin "2"
		)
		(instances
			(project "jetson-orin-baseboard"
				(path ""
					(reference "R219")
					(unit 1)
				)
			)
		)
	)
	(symbol
		(lib_id "antmicropower:GND")
		(at 334.01 137.16 0)
		(unit 1)
		(exclude_from_sim no)
		(in_bom yes)
		(on_board yes)
		(dnp no)
		(fields_autoplaced yes)
		(property "Reference" "#PWR0240"
			(at 334.01 143.51 0)
			(effects
				(font
					(size 1.27 1.27)
				)
				(justify left bottom)
				(hide yes)
			)
		)
		(property "Value" "GND"
			(at 334.01 140.97 0)
			(effects
				(font
					(size 1.27 1.27)
					(thickness 0.15)
				)
			)
		)
		(property "Footprint" ""
			(at 342.9 144.78 0)
			(effects
				(font
					(size 1.27 1.27)
					(thickness 0.15)
				)
				(justify left bottom)
				(hide yes)
			)
		)
		(property "Datasheet" ""
			(at 342.9 149.86 0)
			(effects
				(font
					(size 1.27 1.27)
					(thickness 0.15)
				)
				(justify left bottom)
				(hide yes)
			)
		)
		(property "Description" ""
			(at 334.01 137.16 0)
			(effects
				(font
					(size 1.27 1.27)
				)
				(hide yes)
			)
		)
		(property "Author" "Antmicro"
			(at 342.9 144.78 0)
			(effects
				(font
					(size 1.27 1.27)
					(thickness 0.15)
				)
				(justify left bottom)
				(hide yes)
			)
		)
		(property "License" "Apache-2.0"
			(at 342.9 147.32 0)
			(effects
				(font
					(size 1.27 1.27)
					(thickness 0.15)
				)
				(justify left bottom)
				(hide yes)
			)
		)
		(pin "1"
		)
		(instances
			(project "jetson-orin-baseboard"
				(path ""
					(reference "#PWR0240")
					(unit 1)
				)
			)
		)
	)
	(symbol
		(lib_id "antmicropower:GND")
		(at 267.97 246.38 0)
		(unit 1)
		(exclude_from_sim no)
		(in_bom yes)
		(on_board yes)
		(dnp no)
		(fields_autoplaced yes)
		(property "Reference" "#PWR0314"
			(at 267.97 252.73 0)
			(effects
				(font
					(size 1.27 1.27)
				)
				(justify left bottom)
				(hide yes)
			)
		)
		(property "Value" "GND"
			(at 267.97 250.19 0)
			(effects
				(font
					(size 1.27 1.27)
					(thickness 0.15)
				)
			)
		)
		(property "Footprint" ""
			(at 276.86 254 0)
			(effects
				(font
					(size 1.27 1.27)
					(thickness 0.15)
				)
				(justify left bottom)
				(hide yes)
			)
		)
		(property "Datasheet" ""
			(at 276.86 259.08 0)
			(effects
				(font
					(size 1.27 1.27)
					(thickness 0.15)
				)
				(justify left bottom)
				(hide yes)
			)
		)
		(property "Description" ""
			(at 267.97 246.38 0)
			(effects
				(font
					(size 1.27 1.27)
				)
				(hide yes)
			)
		)
		(property "Author" "Antmicro"
			(at 276.86 254 0)
			(effects
				(font
					(size 1.27 1.27)
					(thickness 0.15)
				)
				(justify left bottom)
				(hide yes)
			)
		)
		(property "License" "Apache-2.0"
			(at 276.86 256.54 0)
			(effects
				(font
					(size 1.27 1.27)
					(thickness 0.15)
				)
				(justify left bottom)
				(hide yes)
			)
		)
		(pin "1"
		)
		(instances
			(project "jetson-orin-baseboard"
				(path ""
					(reference "#PWR0314")
					(unit 1)
				)
			)
		)
	)
	(symbol
		(lib_id "antmicroResistorNetworksArrays:R_4x330R_0402_array")
		(at 132.08 173.99 0)
		(mirror y)
		(unit 1)
		(exclude_from_sim no)
		(in_bom yes)
		(on_board yes)
		(dnp no)
		(property "Reference" "R54"
			(at 127 168.275 0)
			(effects
				(font
					(size 1.27 1.27)
				)
			)
		)
		(property "Value" "R_4x330R_0402_array"
			(at 105.41 179.07 0)
			(effects
				(font
					(size 1.27 1.27)
					(thickness 0.15)
				)
				(justify left bottom)
				(hide yes)
			)
		)
		(property "Footprint" "antmicro-footprints:R_Array_4x0402"
			(at 105.41 184.15 0)
			(effects
				(font
					(size 1.27 1.27)
					(thickness 0.15)
				)
				(justify left bottom)
				(hide yes)
			)
		)
		(property "Datasheet" "http://industrial.panasonic.com/cdbs/www-data/pdf/AOC0000/AOC0000C14.pdf"
			(at 105.41 186.69 0)
			(effects
				(font
					(size 1.27 1.27)
					(thickness 0.15)
				)
				(justify left bottom)
				(hide yes)
			)
		)
		(property "Description" ""
			(at 132.08 173.99 0)
			(effects
				(font
					(size 1.27 1.27)
				)
				(hide yes)
			)
		)
		(property "MPN" "EXB-28V331JX"
			(at 105.41 189.23 0)
			(effects
				(font
					(size 1.27 1.27)
					(thickness 0.15)
				)
				(justify left bottom)
				(hide yes)
			)
		)
		(property "Manufacturer" "Panasonic"
			(at 105.41 191.77 0)
			(effects
				(font
					(size 1.27 1.27)
					(thickness 0.15)
				)
				(justify left bottom)
				(hide yes)
			)
		)
		(property "Author" "Antmicro"
			(at 105.41 194.31 0)
			(effects
				(font
					(size 1.27 1.27)
					(thickness 0.15)
				)
				(justify left bottom)
				(hide yes)
			)
		)
		(property "License" "Apache-2.0"
			(at 105.41 196.85 0)
			(effects
				(font
					(size 1.27 1.27)
					(thickness 0.15)
				)
				(justify left bottom)
				(hide yes)
			)
		)
		(property "Val" "R_4x330R_0402"
			(at 127 170.815 0)
			(effects
				(font
					(size 1.27 1.27)
				)
			)
		)
		(pin "1"
		)
		(pin "2"
		)
		(pin "3"
		)
		(pin "4"
		)
		(pin "5"
		)
		(pin "6"
		)
		(pin "7"
		)
		(pin "8"
		)
		(instances
			(project "jetson-orin-baseboard"
				(path ""
					(reference "R54")
					(unit 1)
				)
			)
		)
	)
	(symbol
		(lib_id "antmicroResistors0402:R_100k_0402")
		(at 140.97 260.35 270)
		(mirror x)
		(unit 1)
		(exclude_from_sim no)
		(in_bom yes)
		(on_board yes)
		(dnp no)
		(property "Reference" "R222"
			(at 139.7 256.54 90)
			(effects
				(font
					(size 1.27 1.27)
				)
				(justify right)
			)
		)
		(property "Value" "R_100k_0402"
			(at 128.27 240.03 0)
			(effects
				(font
					(size 1.27 1.27)
					(thickness 0.15)
				)
				(justify left bottom)
				(hide yes)
			)
		)
		(property "Footprint" "antmicro-footprints:R_0402_1005Metric"
			(at 125.73 240.03 0)
			(effects
				(font
					(size 1.27 1.27)
					(thickness 0.15)
				)
				(justify left bottom)
				(hide yes)
			)
		)
		(property "Datasheet" "https://www.bourns.com/docs/product-datasheets/cr.pdf"
			(at 123.19 240.03 0)
			(effects
				(font
					(size 1.27 1.27)
					(thickness 0.15)
				)
				(justify left bottom)
				(hide yes)
			)
		)
		(property "Description" ""
			(at 140.97 260.35 0)
			(effects
				(font
					(size 1.27 1.27)
				)
				(hide yes)
			)
		)
		(property "Manufacturer" "Bourns"
			(at 118.11 240.03 0)
			(effects
				(font
					(size 1.27 1.27)
					(thickness 0.15)
				)
				(justify left bottom)
				(hide yes)
			)
		)
		(property "MPN" "CR0402-FX-1003GLF"
			(at 120.65 240.03 0)
			(effects
				(font
					(size 1.27 1.27)
					(thickness 0.15)
				)
				(justify left bottom)
				(hide yes)
			)
		)
		(property "Val" "100k"
			(at 139.7 259.08 90)
			(effects
				(font
					(size 1.27 1.27)
					(thickness 0.15)
				)
				(justify right)
			)
		)
		(property "License" "Apache-2.0"
			(at 115.57 240.03 0)
			(effects
				(font
					(size 1.27 1.27)
					(thickness 0.15)
				)
				(justify left bottom)
				(hide yes)
			)
		)
		(property "Author" "Antmicro"
			(at 113.03 240.03 0)
			(effects
				(font
					(size 1.27 1.27)
					(thickness 0.15)
				)
				(justify left bottom)
				(hide yes)
			)
		)
		(property "Tolerance" "1%"
			(at 130.81 240.03 0)
			(effects
				(font
					(size 1.27 1.27)
				)
				(justify left bottom)
				(hide yes)
			)
		)
		(pin "1"
		)
		(pin "2"
		)
		(instances
			(project "jetson-orin-baseboard"
				(path ""
					(reference "R222")
					(unit 1)
				)
			)
		)
	)
	(symbol
		(lib_id "antmicroResistors0402:R_0R_0402")
		(at 284.48 86.36 0)
		(mirror y)
		(unit 1)
		(exclude_from_sim no)
		(in_bom no)
		(on_board yes)
		(dnp yes)
		(property "Reference" "R134"
			(at 284.48 85.725 0)
			(effects
				(font
					(size 1.27 1.27)
				)
				(justify right bottom)
			)
		)
		(property "Value" "R_0R_0402"
			(at 264.16 99.06 0)
			(effects
				(font
					(size 1.27 1.27)
					(thickness 0.15)
				)
				(justify left bottom)
				(hide yes)
			)
		)
		(property "Footprint" "antmicro-footprints:R_0402_1005Metric"
			(at 264.16 101.6 0)
			(effects
				(font
					(size 1.27 1.27)
					(thickness 0.15)
				)
				(justify left bottom)
				(hide yes)
			)
		)
		(property "Datasheet" "https://industrial.panasonic.com/cdbs/www-data/pdf/RDA0000/AOA0000C301.pdf"
			(at 264.16 104.14 0)
			(effects
				(font
					(size 1.27 1.27)
					(thickness 0.15)
				)
				(justify left bottom)
				(hide yes)
			)
		)
		(property "Description" ""
			(at 284.48 86.36 0)
			(effects
				(font
					(size 1.27 1.27)
				)
				(hide yes)
			)
		)
		(property "Manufacturer" "Panasonic"
			(at 264.16 109.22 0)
			(effects
				(font
					(size 1.27 1.27)
					(thickness 0.15)
				)
				(justify left bottom)
				(hide yes)
			)
		)
		(property "MPN" "ERJ2GE0R00X"
			(at 264.16 106.68 0)
			(effects
				(font
					(size 1.27 1.27)
					(thickness 0.15)
				)
				(justify left bottom)
				(hide yes)
			)
		)
		(property "Val" "0R"
			(at 276.86 85.725 0)
			(effects
				(font
					(size 1.27 1.27)
					(thickness 0.15)
				)
				(justify right bottom)
			)
		)
		(property "License" "Apache-2.0"
			(at 264.16 111.76 0)
			(effects
				(font
					(size 1.27 1.27)
					(thickness 0.15)
				)
				(justify left bottom)
				(hide yes)
			)
		)
		(property "Author" "Antmicro"
			(at 264.16 114.3 0)
			(effects
				(font
					(size 1.27 1.27)
					(thickness 0.15)
				)
				(justify left bottom)
				(hide yes)
			)
		)
		(property "Tolerance" "~"
			(at 264.16 96.52 0)
			(effects
				(font
					(size 1.27 1.27)
				)
				(justify left bottom)
				(hide yes)
			)
		)
		(property "Current" "1A"
			(at 264.16 116.84 0)
			(effects
				(font
					(size 1.27 1.27)
					(thickness 0.15)
				)
				(justify left bottom)
				(hide yes)
			)
		)
		(pin "1"
		)
		(pin "2"
		)
		(instances
			(project "jetson-orin-baseboard"
				(path ""
					(reference "R134")
					(unit 1)
				)
			)
		)
	)
	(symbol
		(lib_id "antmicropower:+1V8")
		(at 44.45 53.34 0)
		(unit 1)
		(exclude_from_sim no)
		(in_bom yes)
		(on_board yes)
		(dnp no)
		(property "Reference" "#PWR0219"
			(at 44.45 57.15 0)
			(effects
				(font
					(size 1.27 1.27)
				)
				(justify left bottom)
				(hide yes)
			)
		)
		(property "Value" "+1V8"
			(at 41.275 49.53 0)
			(effects
				(font
					(size 1.27 1.27)
					(thickness 0.15)
				)
				(justify left)
			)
		)
		(property "Footprint" ""
			(at 59.69 60.96 0)
			(effects
				(font
					(size 1.27 1.27)
					(thickness 0.15)
				)
				(justify left bottom)
				(hide yes)
			)
		)
		(property "Datasheet" ""
			(at 59.69 63.5 0)
			(effects
				(font
					(size 1.27 1.27)
					(thickness 0.15)
				)
				(justify left bottom)
				(hide yes)
			)
		)
		(property "Description" ""
			(at 44.45 53.34 0)
			(effects
				(font
					(size 1.27 1.27)
				)
				(hide yes)
			)
		)
		(property "Author" "Antmicro"
			(at 59.69 58.42 0)
			(effects
				(font
					(size 1.27 1.27)
					(thickness 0.15)
				)
				(justify left bottom)
				(hide yes)
			)
		)
		(property "License" "Apache-2.0"
			(at 59.69 60.96 0)
			(effects
				(font
					(size 1.27 1.27)
					(thickness 0.15)
				)
				(justify left bottom)
				(hide yes)
			)
		)
		(pin "1"
		)
		(instances
			(project "jetson-orin-baseboard"
				(path ""
					(reference "#PWR0219")
					(unit 1)
				)
			)
		)
	)
	(symbol
		(lib_id "antmicroResistorNetworksArrays:R_4x330R_0402_array")
		(at 199.39 163.83 180)
		(unit 1)
		(exclude_from_sim no)
		(in_bom yes)
		(on_board yes)
		(dnp no)
		(property "Reference" "R100"
			(at 194.31 150.495 0)
			(effects
				(font
					(size 1.27 1.27)
				)
			)
		)
		(property "Value" "R_4x330R_0402_array"
			(at 172.72 158.75 0)
			(effects
				(font
					(size 1.27 1.27)
					(thickness 0.15)
				)
				(justify left bottom)
				(hide yes)
			)
		)
		(property "Footprint" "antmicro-footprints:R_Array_4x0402"
			(at 172.72 153.67 0)
			(effects
				(font
					(size 1.27 1.27)
					(thickness 0.15)
				)
				(justify left bottom)
				(hide yes)
			)
		)
		(property "Datasheet" "http://industrial.panasonic.com/cdbs/www-data/pdf/AOC0000/AOC0000C14.pdf"
			(at 172.72 151.13 0)
			(effects
				(font
					(size 1.27 1.27)
					(thickness 0.15)
				)
				(justify left bottom)
				(hide yes)
			)
		)
		(property "Description" ""
			(at 199.39 163.83 0)
			(effects
				(font
					(size 1.27 1.27)
				)
				(hide yes)
			)
		)
		(property "MPN" "EXB-28V331JX"
			(at 172.72 148.59 0)
			(effects
				(font
					(size 1.27 1.27)
					(thickness 0.15)
				)
				(justify left bottom)
				(hide yes)
			)
		)
		(property "Manufacturer" "Panasonic"
			(at 172.72 146.05 0)
			(effects
				(font
					(size 1.27 1.27)
					(thickness 0.15)
				)
				(justify left bottom)
				(hide yes)
			)
		)
		(property "Author" "Antmicro"
			(at 172.72 143.51 0)
			(effects
				(font
					(size 1.27 1.27)
					(thickness 0.15)
				)
				(justify left bottom)
				(hide yes)
			)
		)
		(property "License" "Apache-2.0"
			(at 172.72 140.97 0)
			(effects
				(font
					(size 1.27 1.27)
					(thickness 0.15)
				)
				(justify left bottom)
				(hide yes)
			)
		)
		(property "Val" "R_4x330R_0402"
			(at 194.31 153.035 0)
			(effects
				(font
					(size 1.27 1.27)
				)
			)
		)
		(pin "1"
		)
		(pin "2"
		)
		(pin "3"
		)
		(pin "4"
		)
		(pin "5"
		)
		(pin "6"
		)
		(pin "7"
		)
		(pin "8"
		)
		(instances
			(project "jetson-orin-baseboard"
				(path ""
					(reference "R100")
					(unit 1)
				)
			)
		)
	)
	(symbol
		(lib_id "antmicroTVSDiodes:TPD1E0B04_XDFN-2")
		(at 185.42 96.52 90)
		(unit 1)
		(exclude_from_sim no)
		(in_bom yes)
		(on_board yes)
		(dnp no)
		(fields_autoplaced yes)
		(property "Reference" "D56"
			(at 182.88 91.0034 90)
			(effects
				(font
					(size 1.27 1.27)
				)
				(justify left)
			)
		)
		(property "Value" "TPD1E0B04_XDFN-2"
			(at 195.58 81.28 0)
			(effects
				(font
					(size 1.27 1.27)
					(thickness 0.15)
				)
				(justify left bottom)
				(hide yes)
			)
		)
		(property "Footprint" "antmicro-footprints:XDFN-2_1x0.60mm"
			(at 190.5 81.28 0)
			(effects
				(font
					(size 1.27 1.27)
					(thickness 0.15)
				)
				(justify left bottom)
				(hide yes)
			)
		)
		(property "Datasheet" "https://www.ti.com/general/docs/suppproductinfo.tsp?distId=26&gotoUrl=https://www.ti.com/lit/gpn/tpd1e0b04"
			(at 193.04 81.28 0)
			(effects
				(font
					(size 1.27 1.27)
					(thickness 0.15)
				)
				(justify left bottom)
				(hide yes)
			)
		)
		(property "Description" ""
			(at 185.42 96.52 0)
			(effects
				(font
					(size 1.27 1.27)
				)
				(hide yes)
			)
		)
		(property "Manufacturer" "Texas Instruments"
			(at 198.12 81.28 0)
			(effects
				(font
					(size 1.27 1.27)
					(thickness 0.15)
				)
				(justify left bottom)
				(hide yes)
			)
		)
		(property "MPN" "TPD1E0B04DPYR"
			(at 182.88 93.5434 90)
			(effects
				(font
					(size 1.27 1.27)
					(thickness 0.15)
				)
				(justify left)
			)
		)
		(property "Author" "Antmicro"
			(at 200.66 81.28 0)
			(effects
				(font
					(size 1.27 1.27)
					(thickness 0.15)
				)
				(justify left bottom)
				(hide yes)
			)
		)
		(property "License" "Apache-2.0"
			(at 203.2 81.28 0)
			(effects
				(font
					(size 1.27 1.27)
					(thickness 0.15)
				)
				(justify left bottom)
				(hide yes)
			)
		)
		(pin "1"
		)
		(pin "2"
		)
		(instances
			(project "jetson-orin-baseboard"
				(path ""
					(reference "D56")
					(unit 1)
				)
			)
		)
	)
	(symbol
		(lib_id "antmicropower:+1V8")
		(at 29.21 148.59 0)
		(unit 1)
		(exclude_from_sim no)
		(in_bom yes)
		(on_board yes)
		(dnp no)
		(property "Reference" "#PWR0225"
			(at 29.21 152.4 0)
			(effects
				(font
					(size 1.27 1.27)
				)
				(justify left bottom)
				(hide yes)
			)
		)
		(property "Value" "+1V8"
			(at 26.035 145.415 0)
			(effects
				(font
					(size 1.27 1.27)
					(thickness 0.15)
				)
				(justify left bottom)
			)
		)
		(property "Footprint" ""
			(at 44.45 156.21 0)
			(effects
				(font
					(size 1.27 1.27)
					(thickness 0.15)
				)
				(justify left bottom)
				(hide yes)
			)
		)
		(property "Datasheet" ""
			(at 44.45 158.75 0)
			(effects
				(font
					(size 1.27 1.27)
					(thickness 0.15)
				)
				(justify left bottom)
				(hide yes)
			)
		)
		(property "Description" ""
			(at 29.21 148.59 0)
			(effects
				(font
					(size 1.27 1.27)
				)
				(hide yes)
			)
		)
		(property "Author" "Antmicro"
			(at 44.45 153.67 0)
			(effects
				(font
					(size 1.27 1.27)
					(thickness 0.15)
				)
				(justify left bottom)
				(hide yes)
			)
		)
		(property "License" "Apache-2.0"
			(at 44.45 156.21 0)
			(effects
				(font
					(size 1.27 1.27)
					(thickness 0.15)
				)
				(justify left bottom)
				(hide yes)
			)
		)
		(pin "1"
		)
		(instances
			(project "jetson-orin-baseboard"
				(path ""
					(reference "#PWR0225")
					(unit 1)
				)
			)
		)
	)
	(symbol
		(lib_id "antmicroTransistorsFETsMOSFETsSingle:PJE138K")
		(at 201.93 254 0)
		(unit 1)
		(exclude_from_sim no)
		(in_bom yes)
		(on_board yes)
		(dnp no)
		(property "Reference" "Q10"
			(at 210.82 250.19 0)
			(effects
				(font
					(size 1.27 1.27)
					(thickness 0.15)
				)
				(justify left)
			)
		)
		(property "Value" "PJE138K"
			(at 224.79 262.89 0)
			(effects
				(font
					(size 1.27 1.27)
					(thickness 0.15)
				)
				(justify left bottom)
				(hide yes)
			)
		)
		(property "Footprint" "antmicro-footprints:SOT-523"
			(at 224.79 265.43 0)
			(effects
				(font
					(size 1.27 1.27)
					(thickness 0.15)
				)
				(justify left bottom)
				(hide yes)
			)
		)
		(property "Datasheet" "https://www.mouser.com/datasheet/2/1057/PJE138K-1876698.pdf"
			(at 224.79 267.97 0)
			(effects
				(font
					(size 1.27 1.27)
					(thickness 0.15)
				)
				(justify left bottom)
				(hide yes)
			)
		)
		(property "Description" ""
			(at 201.93 254 0)
			(effects
				(font
					(size 1.27 1.27)
				)
				(hide yes)
			)
		)
		(property "MPN" "PJE138K_R1_00001"
			(at 210.82 252.73 0)
			(effects
				(font
					(size 1.27 1.27)
					(thickness 0.15)
				)
				(justify left)
			)
		)
		(property "Manufacturer" "PANJIT"
			(at 224.79 273.05 0)
			(effects
				(font
					(size 1.27 1.27)
					(thickness 0.15)
				)
				(justify left bottom)
				(hide yes)
			)
		)
		(property "Author" "Antmicro"
			(at 224.79 275.59 0)
			(effects
				(font
					(size 1.27 1.27)
					(thickness 0.15)
				)
				(justify left bottom)
				(hide yes)
			)
		)
		(property "License" "Apache-2.0"
			(at 224.79 278.13 0)
			(effects
				(font
					(size 1.27 1.27)
					(thickness 0.15)
				)
				(justify left bottom)
				(hide yes)
			)
		)
		(pin "2"
		)
		(pin "3"
		)
		(pin "1"
		)
		(instances
			(project "jetson-orin-baseboard"
				(path ""
					(reference "Q10")
					(unit 1)
				)
			)
		)
	)
	(symbol
		(lib_id "antmicropower:GND")
		(at 149.86 261.62 0)
		(unit 1)
		(exclude_from_sim no)
		(in_bom yes)
		(on_board yes)
		(dnp no)
		(fields_autoplaced yes)
		(property "Reference" "#PWR0229"
			(at 149.86 267.97 0)
			(effects
				(font
					(size 1.27 1.27)
				)
				(justify left bottom)
				(hide yes)
			)
		)
		(property "Value" "GND"
			(at 149.86 265.43 0)
			(effects
				(font
					(size 1.27 1.27)
					(thickness 0.15)
				)
			)
		)
		(property "Footprint" ""
			(at 158.75 269.24 0)
			(effects
				(font
					(size 1.27 1.27)
					(thickness 0.15)
				)
				(justify left bottom)
				(hide yes)
			)
		)
		(property "Datasheet" ""
			(at 158.75 274.32 0)
			(effects
				(font
					(size 1.27 1.27)
					(thickness 0.15)
				)
				(justify left bottom)
				(hide yes)
			)
		)
		(property "Description" ""
			(at 149.86 261.62 0)
			(effects
				(font
					(size 1.27 1.27)
				)
				(hide yes)
			)
		)
		(property "Author" "Antmicro"
			(at 158.75 269.24 0)
			(effects
				(font
					(size 1.27 1.27)
					(thickness 0.15)
				)
				(justify left bottom)
				(hide yes)
			)
		)
		(property "License" "Apache-2.0"
			(at 158.75 271.78 0)
			(effects
				(font
					(size 1.27 1.27)
					(thickness 0.15)
				)
				(justify left bottom)
				(hide yes)
			)
		)
		(pin "1"
		)
		(instances
			(project "jetson-orin-baseboard"
				(path ""
					(reference "#PWR0229")
					(unit 1)
				)
			)
		)
	)
	(symbol
		(lib_id "antmicroLEDIndicationDiscrete:LED_G_0603_LTST-C190GKT")
		(at 208.28 245.11 90)
		(unit 1)
		(exclude_from_sim no)
		(in_bom yes)
		(on_board yes)
		(dnp no)
		(property "Reference" "D27"
			(at 209.55 241.3 90)
			(effects
				(font
					(size 1.27 1.27)
				)
				(justify right)
			)
		)
		(property "Value" "LED_G_0603_LTST-C190GKT"
			(at 215.9 222.25 0)
			(effects
				(font
					(size 1.27 1.27)
					(thickness 0.15)
				)
				(justify left bottom)
				(hide yes)
			)
		)
		(property "Footprint" "antmicro-footprints:LED_0603_1608Metric_G"
			(at 218.44 222.25 0)
			(effects
				(font
					(size 1.27 1.27)
					(thickness 0.15)
				)
				(justify left bottom)
				(hide yes)
			)
		)
		(property "Datasheet" "https://media.digikey.com/pdf/Data%20Sheets/Lite-On%20PDFs/LTST-C190GKT.pdf"
			(at 220.98 222.25 0)
			(effects
				(font
					(size 1.27 1.27)
					(thickness 0.15)
				)
				(justify left bottom)
				(hide yes)
			)
		)
		(property "Description" ""
			(at 208.28 245.11 0)
			(effects
				(font
					(size 1.27 1.27)
				)
				(hide yes)
			)
		)
		(property "MPN" "LTST-C190GKT"
			(at 223.52 222.25 0)
			(effects
				(font
					(size 1.27 1.27)
					(thickness 0.15)
				)
				(justify left bottom)
				(hide yes)
			)
		)
		(property "Manufacturer" "Lite-On"
			(at 226.06 222.25 0)
			(effects
				(font
					(size 1.27 1.27)
					(thickness 0.15)
				)
				(justify left bottom)
				(hide yes)
			)
		)
		(property "Author" "Antmicro"
			(at 228.6 222.25 0)
			(effects
				(font
					(size 1.27 1.27)
					(thickness 0.15)
				)
				(justify left bottom)
				(hide yes)
			)
		)
		(property "License" "Apache-2.0"
			(at 231.14 222.25 0)
			(effects
				(font
					(size 1.27 1.27)
					(thickness 0.15)
				)
				(justify left bottom)
				(hide yes)
			)
		)
		(property "Color" "Green"
			(at 209.55 243.84 90)
			(effects
				(font
					(size 1.27 1.27)
				)
				(justify right)
			)
		)
		(pin "1"
		)
		(pin "2"
		)
		(instances
			(project "jetson-orin-baseboard"
				(path ""
					(reference "D27")
					(unit 1)
				)
			)
		)
	)
	(symbol
		(lib_id "antmicroResistors0603:R_0R_22.4A_0603")
		(at 262.89 173.99 90)
		(unit 1)
		(exclude_from_sim no)
		(in_bom yes)
		(on_board yes)
		(dnp no)
		(property "Reference" "R235"
			(at 264.16 170.18 90)
			(effects
				(font
					(size 1.27 1.27)
				)
				(justify right)
			)
		)
		(property "Value" "R_0R_22.4A_0603"
			(at 255.905 158.115 0)
			(effects
				(font
					(size 1.27 1.27)
					(thickness 0.15)
				)
				(hide yes)
			)
		)
		(property "Footprint" "antmicro-footprints:R_0603_1608Metric"
			(at 273.05 158.75 0)
			(effects
				(font
					(size 1.27 1.27)
					(thickness 0.15)
				)
				(justify left bottom)
				(hide yes)
			)
		)
		(property "Datasheet" "https://fscdn.rohm.com/en/products/databook/datasheet/passive/resistor/chip_resistor/pmr-jpw-e.pdf"
			(at 275.59 158.75 0)
			(effects
				(font
					(size 1.27 1.27)
					(thickness 0.15)
				)
				(justify left bottom)
				(hide yes)
			)
		)
		(property "Description" ""
			(at 262.89 173.99 0)
			(effects
				(font
					(size 1.27 1.27)
				)
				(hide yes)
			)
		)
		(property "Manufacturer" "ROHM Semiconductor"
			(at 280.67 158.75 0)
			(effects
				(font
					(size 1.27 1.27)
					(thickness 0.15)
				)
				(justify left bottom)
				(hide yes)
			)
		)
		(property "MPN" "PMR03EZPJ000"
			(at 278.13 158.75 0)
			(effects
				(font
					(size 1.27 1.27)
					(thickness 0.15)
				)
				(justify left bottom)
				(hide yes)
			)
		)
		(property "Val" "0R"
			(at 264.16 172.72 90)
			(effects
				(font
					(size 1.27 1.27)
					(thickness 0.15)
				)
				(justify right)
			)
		)
		(property "Author" "Antmicro"
			(at 285.75 158.75 0)
			(effects
				(font
					(size 1.27 1.27)
					(thickness 0.15)
				)
				(justify left bottom)
				(hide yes)
			)
		)
		(property "License" "Apache-2.0"
			(at 288.29 158.75 0)
			(effects
				(font
					(size 1.27 1.27)
					(thickness 0.15)
				)
				(justify left bottom)
				(hide yes)
			)
		)
		(property "Max. Curr." "22.4A"
			(at 260.985 168.275 0)
			(effects
				(font
					(size 1.27 1.27)
					(thickness 0.15)
				)
				(justify right)
			)
		)
		(property "Tolerance" "template_tolerance"
			(at 273.05 153.67 0)
			(effects
				(font
					(size 1.27 1.27)
				)
				(justify left bottom)
				(hide yes)
			)
		)
		(pin "1"
		)
		(pin "2"
		)
		(instances
			(project "jetson-orin-baseboard"
				(path ""
					(reference "R235")
					(unit 1)
				)
			)
		)
	)
	(symbol
		(lib_id "antmicroInterfaceIOExpanders:PCAL6408A_VQFN")
		(at 68.58 60.96 0)
		(unit 1)
		(exclude_from_sim no)
		(in_bom yes)
		(on_board yes)
		(dnp no)
		(property "Reference" "U34"
			(at 78.74 54.61 0)
			(effects
				(font
					(size 1.27 1.27)
				)
			)
		)
		(property "Value" "PCAL6408A_VQFN"
			(at 104.14 68.58 0)
			(effects
				(font
					(size 1.27 1.27)
					(thickness 0.15)
				)
				(justify left bottom)
				(hide yes)
			)
		)
		(property "Footprint" "antmicro-footprints:VQFN-16-1EP_3x3mm_P0.5mm_EP1.68x1.68mm"
			(at 104.14 71.12 0)
			(effects
				(font
					(size 1.27 1.27)
					(thickness 0.15)
				)
				(justify left bottom)
				(hide yes)
			)
		)
		(property "Datasheet" "https://eu.mouser.com/datasheet/2/302/PCAL6408A-3139197.pdf"
			(at 104.14 73.66 0)
			(effects
				(font
					(size 1.27 1.27)
					(thickness 0.15)
				)
				(justify left bottom)
				(hide yes)
			)
		)
		(property "Description" ""
			(at 68.58 60.96 0)
			(effects
				(font
					(size 1.27 1.27)
				)
				(hide yes)
			)
		)
		(property "MPN" "PCAL6408ABSHP"
			(at 78.74 57.15 0)
			(effects
				(font
					(size 1.27 1.27)
					(thickness 0.15)
				)
			)
		)
		(property "Manufacturer" "NXP"
			(at 104.14 76.2 0)
			(effects
				(font
					(size 1.27 1.27)
					(thickness 0.15)
				)
				(justify left bottom)
				(hide yes)
			)
		)
		(property "Author" "Antmicro"
			(at 104.14 78.74 0)
			(effects
				(font
					(size 1.27 1.27)
					(thickness 0.15)
				)
				(justify left bottom)
				(hide yes)
			)
		)
		(property "License" "Apache-2.0"
			(at 104.14 81.28 0)
			(effects
				(font
					(size 1.27 1.27)
					(thickness 0.15)
				)
				(justify left bottom)
				(hide yes)
			)
		)
		(pin "1"
		)
		(pin "10"
		)
		(pin "11"
		)
		(pin "12"
		)
		(pin "13"
		)
		(pin "14"
		)
		(pin "15"
		)
		(pin "16"
		)
		(pin "17"
		)
		(pin "2"
		)
		(pin "3"
		)
		(pin "4"
		)
		(pin "5"
		)
		(pin "6"
		)
		(pin "7"
		)
		(pin "8"
		)
		(pin "9"
		)
		(instances
			(project "jetson-orin-baseboard"
				(path ""
					(reference "U34")
					(unit 1)
				)
			)
		)
	)
	(symbol
		(lib_id "antmicroResistors0402:R_470R_0402")
		(at 349.25 121.92 180)
		(unit 1)
		(exclude_from_sim no)
		(in_bom yes)
		(on_board yes)
		(dnp no)
		(property "Reference" "R336"
			(at 349.25 121.285 0)
			(effects
				(font
					(size 1.27 1.27)
				)
				(justify right top)
			)
		)
		(property "Value" "R_470R_0402"
			(at 328.93 109.22 0)
			(effects
				(font
					(size 1.27 1.27)
					(thickness 0.15)
				)
				(justify left bottom)
				(hide yes)
			)
		)
		(property "Footprint" "antmicro-footprints:R_0402_1005Metric"
			(at 328.93 106.68 0)
			(effects
				(font
					(size 1.27 1.27)
					(thickness 0.15)
				)
				(justify left bottom)
				(hide yes)
			)
		)
		(property "Datasheet" "https://www.bourns.com/docs/product-datasheets/cr.pdf"
			(at 328.93 104.14 0)
			(effects
				(font
					(size 1.27 1.27)
					(thickness 0.15)
				)
				(justify left bottom)
				(hide yes)
			)
		)
		(property "Description" ""
			(at 349.25 121.92 0)
			(effects
				(font
					(size 1.27 1.27)
				)
				(hide yes)
			)
		)
		(property "Manufacturer" "Bourns"
			(at 328.93 99.06 0)
			(effects
				(font
					(size 1.27 1.27)
					(thickness 0.15)
				)
				(justify left bottom)
				(hide yes)
			)
		)
		(property "MPN" "CR0402-FX-4700GLF"
			(at 328.93 101.6 0)
			(effects
				(font
					(size 1.27 1.27)
					(thickness 0.15)
				)
				(justify left bottom)
				(hide yes)
			)
		)
		(property "Val" "470R"
			(at 339.09 121.285 0)
			(effects
				(font
					(size 1.27 1.27)
					(thickness 0.15)
				)
				(justify right top)
			)
		)
		(property "License" "Apache-2.0"
			(at 328.93 96.52 0)
			(effects
				(font
					(size 1.27 1.27)
					(thickness 0.15)
				)
				(justify left bottom)
				(hide yes)
			)
		)
		(property "Author" "Antmicro"
			(at 328.93 93.98 0)
			(effects
				(font
					(size 1.27 1.27)
					(thickness 0.15)
				)
				(justify left bottom)
				(hide yes)
			)
		)
		(property "Tolerance" "1%"
			(at 328.93 111.76 0)
			(effects
				(font
					(size 1.27 1.27)
				)
				(justify left bottom)
				(hide yes)
			)
		)
		(pin "1"
		)
		(pin "2"
		)
		(instances
			(project "jetson-orin-baseboard"
				(path ""
					(reference "R336")
					(unit 1)
				)
			)
		)
	)
	(symbol
		(lib_id "antmicropower:+3V3")
		(at 57.15 53.34 0)
		(unit 1)
		(exclude_from_sim no)
		(in_bom yes)
		(on_board yes)
		(dnp no)
		(property "Reference" "#PWR0222"
			(at 57.15 57.15 0)
			(effects
				(font
					(size 1.27 1.27)
				)
				(justify left bottom)
				(hide yes)
			)
		)
		(property "Value" "+3V3"
			(at 53.975 49.53 0)
			(effects
				(font
					(size 1.27 1.27)
					(thickness 0.15)
				)
				(justify left)
			)
		)
		(property "Footprint" ""
			(at 72.39 60.96 0)
			(effects
				(font
					(size 1.27 1.27)
					(thickness 0.15)
				)
				(justify left bottom)
				(hide yes)
			)
		)
		(property "Datasheet" ""
			(at 72.39 63.5 0)
			(effects
				(font
					(size 1.27 1.27)
					(thickness 0.15)
				)
				(justify left bottom)
				(hide yes)
			)
		)
		(property "Description" ""
			(at 57.15 53.34 0)
			(effects
				(font
					(size 1.27 1.27)
				)
				(hide yes)
			)
		)
		(property "Author" "Antmicro"
			(at 72.39 55.88 0)
			(effects
				(font
					(size 1.27 1.27)
					(thickness 0.15)
				)
				(justify left bottom)
				(hide yes)
			)
		)
		(property "License" "Apache-2.0"
			(at 72.39 58.42 0)
			(effects
				(font
					(size 1.27 1.27)
					(thickness 0.15)
				)
				(justify left bottom)
				(hide yes)
			)
		)
		(pin "1"
		)
		(instances
			(project "jetson-orin-baseboard"
				(path ""
					(reference "#PWR0222")
					(unit 1)
				)
			)
		)
	)
	(symbol
		(lib_id "antmicropower:GND")
		(at 57.15 62.23 0)
		(unit 1)
		(exclude_from_sim no)
		(in_bom yes)
		(on_board yes)
		(dnp no)
		(fields_autoplaced yes)
		(property "Reference" "#PWR0206"
			(at 57.15 68.58 0)
			(effects
				(font
					(size 1.27 1.27)
				)
				(justify left bottom)
				(hide yes)
			)
		)
		(property "Value" "GND"
			(at 57.15 66.04 0)
			(effects
				(font
					(size 1.27 1.27)
					(thickness 0.15)
				)
			)
		)
		(property "Footprint" ""
			(at 66.04 69.85 0)
			(effects
				(font
					(size 1.27 1.27)
					(thickness 0.15)
				)
				(justify left bottom)
				(hide yes)
			)
		)
		(property "Datasheet" ""
			(at 66.04 74.93 0)
			(effects
				(font
					(size 1.27 1.27)
					(thickness 0.15)
				)
				(justify left bottom)
				(hide yes)
			)
		)
		(property "Description" ""
			(at 57.15 62.23 0)
			(effects
				(font
					(size 1.27 1.27)
				)
				(hide yes)
			)
		)
		(property "Author" "Antmicro"
			(at 66.04 69.85 0)
			(effects
				(font
					(size 1.27 1.27)
					(thickness 0.15)
				)
				(justify left bottom)
				(hide yes)
			)
		)
		(property "License" "Apache-2.0"
			(at 66.04 72.39 0)
			(effects
				(font
					(size 1.27 1.27)
					(thickness 0.15)
				)
				(justify left bottom)
				(hide yes)
			)
		)
		(pin "1"
		)
		(instances
			(project "jetson-orin-baseboard"
				(path ""
					(reference "#PWR0206")
					(unit 1)
				)
			)
		)
	)
	(symbol
		(lib_id "antmicroResistors0402:R_100k_0402")
		(at 162.56 57.15 90)
		(unit 1)
		(exclude_from_sim no)
		(in_bom no)
		(on_board yes)
		(dnp yes)
		(property "Reference" "R192"
			(at 163.83 53.34 90)
			(effects
				(font
					(size 1.27 1.27)
				)
				(justify right)
			)
		)
		(property "Value" "R_100k_0402"
			(at 175.26 36.83 0)
			(effects
				(font
					(size 1.27 1.27)
					(thickness 0.15)
				)
				(justify left bottom)
				(hide yes)
			)
		)
		(property "Footprint" "antmicro-footprints:R_0402_1005Metric"
			(at 177.8 36.83 0)
			(effects
				(font
					(size 1.27 1.27)
					(thickness 0.15)
				)
				(justify left bottom)
				(hide yes)
			)
		)
		(property "Datasheet" "https://www.bourns.com/docs/product-datasheets/cr.pdf"
			(at 180.34 36.83 0)
			(effects
				(font
					(size 1.27 1.27)
					(thickness 0.15)
				)
				(justify left bottom)
				(hide yes)
			)
		)
		(property "Description" ""
			(at 162.56 57.15 0)
			(effects
				(font
					(size 1.27 1.27)
				)
				(hide yes)
			)
		)
		(property "Manufacturer" "Bourns"
			(at 185.42 36.83 0)
			(effects
				(font
					(size 1.27 1.27)
					(thickness 0.15)
				)
				(justify left bottom)
				(hide yes)
			)
		)
		(property "MPN" "CR0402-FX-1003GLF"
			(at 182.88 36.83 0)
			(effects
				(font
					(size 1.27 1.27)
					(thickness 0.15)
				)
				(justify left bottom)
				(hide yes)
			)
		)
		(property "Val" "100k"
			(at 163.83 55.88 90)
			(effects
				(font
					(size 1.27 1.27)
					(thickness 0.15)
				)
				(justify right)
			)
		)
		(property "License" "Apache-2.0"
			(at 187.96 36.83 0)
			(effects
				(font
					(size 1.27 1.27)
					(thickness 0.15)
				)
				(justify left bottom)
				(hide yes)
			)
		)
		(property "Author" "Antmicro"
			(at 190.5 36.83 0)
			(effects
				(font
					(size 1.27 1.27)
					(thickness 0.15)
				)
				(justify left bottom)
				(hide yes)
			)
		)
		(property "Tolerance" "1%"
			(at 172.72 36.83 0)
			(effects
				(font
					(size 1.27 1.27)
				)
				(justify left bottom)
				(hide yes)
			)
		)
		(pin "1"
		)
		(pin "2"
		)
		(instances
			(project "jetson-orin-baseboard"
				(path ""
					(reference "R192")
					(unit 1)
				)
			)
		)
	)
	(symbol
		(lib_id "antmicropower:PWR_FLAG")
		(at 36.83 229.87 0)
		(unit 1)
		(exclude_from_sim no)
		(in_bom yes)
		(on_board yes)
		(dnp no)
		(property "Reference" "#FLG07"
			(at 36.83 227.965 0)
			(effects
				(font
					(size 1.27 1.27)
				)
				(hide yes)
			)
		)
		(property "Value" "PWR_FLAG"
			(at 36.83 226.06 0)
			(effects
				(font
					(size 1.27 1.27)
				)
			)
		)
		(property "Footprint" ""
			(at 36.83 229.87 0)
			(effects
				(font
					(size 1.27 1.27)
				)
				(hide yes)
			)
		)
		(property "Datasheet" ""
			(at 36.83 229.87 0)
			(effects
				(font
					(size 1.27 1.27)
				)
				(hide yes)
			)
		)
		(property "Description" ""
			(at 36.83 229.87 0)
			(effects
				(font
					(size 1.27 1.27)
				)
				(hide yes)
			)
		)
		(pin "1"
		)
		(instances
			(project "jetson-orin-baseboard"
				(path ""
					(reference "#FLG07")
					(unit 1)
				)
			)
		)
	)
	(symbol
		(lib_id "antmicroResistors0603:R_0R_0603")
		(at 295.91 168.91 90)
		(mirror x)
		(unit 1)
		(exclude_from_sim no)
		(in_bom no)
		(on_board yes)
		(dnp yes)
		(property "Reference" "R234"
			(at 297.18 170.18 90)
			(effects
				(font
					(size 1.27 1.27)
				)
				(justify right)
			)
		)
		(property "Value" "R_0R_0603"
			(at 308.61 189.23 0)
			(effects
				(font
					(size 1.27 1.27)
					(thickness 0.15)
				)
				(justify left bottom)
				(hide yes)
			)
		)
		(property "Footprint" "antmicro-footprints:R_0603_1608Metric"
			(at 311.15 189.23 0)
			(effects
				(font
					(size 1.27 1.27)
					(thickness 0.15)
				)
				(justify left bottom)
				(hide yes)
			)
		)
		(property "Datasheet" "https://www.bourns.com/docs/product-datasheets/cr.pdf?sfvrsn=574d41f6_14"
			(at 313.69 189.23 0)
			(effects
				(font
					(size 1.27 1.27)
					(thickness 0.15)
				)
				(justify left bottom)
				(hide yes)
			)
		)
		(property "Description" ""
			(at 295.91 168.91 0)
			(effects
				(font
					(size 1.27 1.27)
				)
				(hide yes)
			)
		)
		(property "Manufacturer" "Bourns"
			(at 318.77 189.23 0)
			(effects
				(font
					(size 1.27 1.27)
					(thickness 0.15)
				)
				(justify left bottom)
				(hide yes)
			)
		)
		(property "MPN" "CR0603-J/-000ELF"
			(at 316.23 189.23 0)
			(effects
				(font
					(size 1.27 1.27)
					(thickness 0.15)
				)
				(justify left bottom)
				(hide yes)
			)
		)
		(property "Val" "0R"
			(at 297.18 172.72 90)
			(effects
				(font
					(size 1.27 1.27)
					(thickness 0.15)
				)
				(justify right)
			)
		)
		(property "License" "Apache-2.0"
			(at 321.31 189.23 0)
			(effects
				(font
					(size 1.27 1.27)
					(thickness 0.15)
				)
				(justify left bottom)
				(hide yes)
			)
		)
		(property "Author" "Antmicro"
			(at 323.85 189.23 0)
			(effects
				(font
					(size 1.27 1.27)
					(thickness 0.15)
				)
				(justify left bottom)
				(hide yes)
			)
		)
		(property "Tolerance" "~"
			(at 306.07 189.23 0)
			(effects
				(font
					(size 1.27 1.27)
				)
				(justify left bottom)
				(hide yes)
			)
		)
		(property "Current" "1A"
			(at 326.39 189.23 0)
			(effects
				(font
					(size 1.27 1.27)
					(thickness 0.15)
				)
				(justify left bottom)
				(hide yes)
			)
		)
		(pin "1"
		)
		(pin "2"
		)
		(instances
			(project "jetson-orin-baseboard"
				(path ""
					(reference "R234")
					(unit 1)
				)
			)
		)
	)
	(symbol
		(lib_id "antmicroTVSDiodes:TPD1E0B04_XDFN-2")
		(at 388.62 187.96 0)
		(unit 1)
		(exclude_from_sim no)
		(in_bom yes)
		(on_board yes)
		(dnp no)
		(property "Reference" "D43"
			(at 393.065 187.325 0)
			(effects
				(font
					(size 1.27 1.27)
				)
				(justify left bottom)
			)
		)
		(property "Value" "TPD1E0B04_XDFN-2"
			(at 403.86 198.12 0)
			(effects
				(font
					(size 1.27 1.27)
					(thickness 0.15)
				)
				(justify left bottom)
				(hide yes)
			)
		)
		(property "Footprint" "antmicro-footprints:XDFN-2_1x0.60mm"
			(at 403.86 193.04 0)
			(effects
				(font
					(size 1.27 1.27)
					(thickness 0.15)
				)
				(justify left bottom)
				(hide yes)
			)
		)
		(property "Datasheet" "https://www.ti.com/general/docs/suppproductinfo.tsp?distId=26&gotoUrl=https://www.ti.com/lit/gpn/tpd1e0b04"
			(at 403.86 195.58 0)
			(effects
				(font
					(size 1.27 1.27)
					(thickness 0.15)
				)
				(justify left bottom)
				(hide yes)
			)
		)
		(property "Description" ""
			(at 388.62 187.96 0)
			(effects
				(font
					(size 1.27 1.27)
				)
				(hide yes)
			)
		)
		(property "Manufacturer" "Texas Instruments"
			(at 403.86 200.66 0)
			(effects
				(font
					(size 1.27 1.27)
					(thickness 0.15)
				)
				(justify left bottom)
				(hide yes)
			)
		)
		(property "MPN" "TPD1E0B04DPYR"
			(at 373.38 187.325 0)
			(effects
				(font
					(size 1.27 1.27)
					(thickness 0.15)
				)
				(justify left bottom)
			)
		)
		(property "Author" "Antmicro"
			(at 403.86 203.2 0)
			(effects
				(font
					(size 1.27 1.27)
					(thickness 0.15)
				)
				(justify left bottom)
				(hide yes)
			)
		)
		(property "License" "Apache-2.0"
			(at 403.86 205.74 0)
			(effects
				(font
					(size 1.27 1.27)
					(thickness 0.15)
				)
				(justify left bottom)
				(hide yes)
			)
		)
		(pin "1"
		)
		(pin "2"
		)
		(instances
			(project "jetson-orin-baseboard"
				(path ""
					(reference "D43")
					(unit 1)
				)
			)
		)
	)
	(symbol
		(lib_id "antmicroCapacitors0402:C_1u_0402")
		(at 262.89 185.42 90)
		(unit 1)
		(exclude_from_sim no)
		(in_bom yes)
		(on_board yes)
		(dnp no)
		(property "Reference" "C107"
			(at 264.795 181.61 90)
			(effects
				(font
					(size 1.27 1.27)
				)
				(justify right)
			)
		)
		(property "Value" "C_1u_0402"
			(at 273.05 165.1 0)
			(effects
				(font
					(size 1.27 1.27)
					(thickness 0.15)
				)
				(justify left bottom)
				(hide yes)
			)
		)
		(property "Footprint" "antmicro-footprints:C_0402_1005Metric"
			(at 275.59 165.1 0)
			(effects
				(font
					(size 1.27 1.27)
					(thickness 0.15)
				)
				(justify left bottom)
				(hide yes)
			)
		)
		(property "Datasheet" "https://product.tdk.com/en/search/capacitor/ceramic/mlcc/info?part_no=C1005X6S1A105K050BC"
			(at 278.13 165.1 0)
			(effects
				(font
					(size 1.27 1.27)
					(thickness 0.15)
				)
				(justify left bottom)
				(hide yes)
			)
		)
		(property "Description" ""
			(at 262.89 185.42 0)
			(effects
				(font
					(size 1.27 1.27)
				)
				(hide yes)
			)
		)
		(property "Manufacturer" "TDK"
			(at 283.21 165.1 0)
			(effects
				(font
					(size 1.27 1.27)
					(thickness 0.15)
				)
				(justify left bottom)
				(hide yes)
			)
		)
		(property "MPN" "C1005X6S1A105K050BC"
			(at 280.67 165.1 0)
			(effects
				(font
					(size 1.27 1.27)
					(thickness 0.15)
				)
				(justify left bottom)
				(hide yes)
			)
		)
		(property "Val" "1u"
			(at 264.795 184.15 90)
			(effects
				(font
					(size 1.27 1.27)
					(thickness 0.15)
				)
				(justify right)
			)
		)
		(property "License" "Apache-2.0"
			(at 285.75 165.1 0)
			(effects
				(font
					(size 1.27 1.27)
					(thickness 0.15)
				)
				(justify left bottom)
				(hide yes)
			)
		)
		(property "Author" "Antmicro"
			(at 288.29 165.1 0)
			(effects
				(font
					(size 1.27 1.27)
					(thickness 0.15)
				)
				(justify left bottom)
				(hide yes)
			)
		)
		(property "Voltage" ""
			(at 290.83 165.1 0)
			(effects
				(font
					(size 1.27 1.27)
				)
				(justify left bottom)
				(hide yes)
			)
		)
		(property "Dielectric" ""
			(at 293.37 165.1 0)
			(effects
				(font
					(size 1.27 1.27)
				)
				(justify left bottom)
				(hide yes)
			)
		)
		(pin "1"
		)
		(pin "2"
		)
		(instances
			(project "jetson-orin-baseboard"
				(path ""
					(reference "C107")
					(unit 1)
				)
			)
		)
	)
	(symbol
		(lib_id "antmicropower:+3V3")
		(at 44.45 81.28 0)
		(unit 1)
		(exclude_from_sim no)
		(in_bom yes)
		(on_board yes)
		(dnp no)
		(property "Reference" "#PWR0179"
			(at 44.45 85.09 0)
			(effects
				(font
					(size 1.27 1.27)
				)
				(justify left bottom)
				(hide yes)
			)
		)
		(property "Value" "+3V3"
			(at 41.275 77.47 0)
			(effects
				(font
					(size 1.27 1.27)
					(thickness 0.15)
				)
				(justify left)
			)
		)
		(property "Footprint" ""
			(at 59.69 88.9 0)
			(effects
				(font
					(size 1.27 1.27)
					(thickness 0.15)
				)
				(justify left bottom)
				(hide yes)
			)
		)
		(property "Datasheet" ""
			(at 59.69 91.44 0)
			(effects
				(font
					(size 1.27 1.27)
					(thickness 0.15)
				)
				(justify left bottom)
				(hide yes)
			)
		)
		(property "Description" ""
			(at 44.45 81.28 0)
			(effects
				(font
					(size 1.27 1.27)
				)
				(hide yes)
			)
		)
		(property "Author" "Antmicro"
			(at 59.69 83.82 0)
			(effects
				(font
					(size 1.27 1.27)
					(thickness 0.15)
				)
				(justify left bottom)
				(hide yes)
			)
		)
		(property "License" "Apache-2.0"
			(at 59.69 86.36 0)
			(effects
				(font
					(size 1.27 1.27)
					(thickness 0.15)
				)
				(justify left bottom)
				(hide yes)
			)
		)
		(pin "1"
		)
		(instances
			(project "jetson-orin-baseboard"
				(path ""
					(reference "#PWR0179")
					(unit 1)
				)
			)
		)
	)
	(symbol
		(lib_id "antmicroResistors0402:R_200R_0402")
		(at 208.28 238.76 90)
		(unit 1)
		(exclude_from_sim no)
		(in_bom yes)
		(on_board yes)
		(dnp no)
		(property "Reference" "R231"
			(at 209.55 234.95 90)
			(effects
				(font
					(size 1.27 1.27)
				)
				(justify right)
			)
		)
		(property "Value" "R_200R_0402"
			(at 220.98 218.44 0)
			(effects
				(font
					(size 1.27 1.27)
					(thickness 0.15)
				)
				(justify left bottom)
				(hide yes)
			)
		)
		(property "Footprint" "antmicro-footprints:R_0402_1005Metric"
			(at 223.52 218.44 0)
			(effects
				(font
					(size 1.27 1.27)
					(thickness 0.15)
				)
				(justify left bottom)
				(hide yes)
			)
		)
		(property "Datasheet" "https://www.bourns.com/docs/product-datasheets/cr.pdf"
			(at 226.06 218.44 0)
			(effects
				(font
					(size 1.27 1.27)
					(thickness 0.15)
				)
				(justify left bottom)
				(hide yes)
			)
		)
		(property "Description" ""
			(at 208.28 238.76 0)
			(effects
				(font
					(size 1.27 1.27)
				)
				(hide yes)
			)
		)
		(property "Manufacturer" "Bourns"
			(at 231.14 218.44 0)
			(effects
				(font
					(size 1.27 1.27)
					(thickness 0.15)
				)
				(justify left bottom)
				(hide yes)
			)
		)
		(property "MPN" "CR0402-FX-2000GLF"
			(at 228.6 218.44 0)
			(effects
				(font
					(size 1.27 1.27)
					(thickness 0.15)
				)
				(justify left bottom)
				(hide yes)
			)
		)
		(property "Val" "200R"
			(at 209.55 237.49 90)
			(effects
				(font
					(size 1.27 1.27)
					(thickness 0.15)
				)
				(justify right)
			)
		)
		(property "License" "Apache-2.0"
			(at 233.68 218.44 0)
			(effects
				(font
					(size 1.27 1.27)
					(thickness 0.15)
				)
				(justify left bottom)
				(hide yes)
			)
		)
		(property "Author" "Antmicro"
			(at 236.22 218.44 0)
			(effects
				(font
					(size 1.27 1.27)
					(thickness 0.15)
				)
				(justify left bottom)
				(hide yes)
			)
		)
		(property "Tolerance" "1%"
			(at 218.44 218.44 0)
			(effects
				(font
					(size 1.27 1.27)
				)
				(justify left bottom)
				(hide yes)
			)
		)
		(pin "1"
		)
		(pin "2"
		)
		(instances
			(project "jetson-orin-baseboard"
				(path ""
					(reference "R231")
					(unit 1)
				)
			)
		)
	)
	(symbol
		(lib_id "antmicropower:GND")
		(at 199.39 261.62 0)
		(unit 1)
		(exclude_from_sim no)
		(in_bom yes)
		(on_board yes)
		(dnp no)
		(fields_autoplaced yes)
		(property "Reference" "#PWR0233"
			(at 199.39 267.97 0)
			(effects
				(font
					(size 1.27 1.27)
				)
				(justify left bottom)
				(hide yes)
			)
		)
		(property "Value" "GND"
			(at 199.39 265.43 0)
			(effects
				(font
					(size 1.27 1.27)
					(thickness 0.15)
				)
			)
		)
		(property "Footprint" ""
			(at 208.28 269.24 0)
			(effects
				(font
					(size 1.27 1.27)
					(thickness 0.15)
				)
				(justify left bottom)
				(hide yes)
			)
		)
		(property "Datasheet" ""
			(at 208.28 274.32 0)
			(effects
				(font
					(size 1.27 1.27)
					(thickness 0.15)
				)
				(justify left bottom)
				(hide yes)
			)
		)
		(property "Description" ""
			(at 199.39 261.62 0)
			(effects
				(font
					(size 1.27 1.27)
				)
				(hide yes)
			)
		)
		(property "Author" "Antmicro"
			(at 208.28 269.24 0)
			(effects
				(font
					(size 1.27 1.27)
					(thickness 0.15)
				)
				(justify left bottom)
				(hide yes)
			)
		)
		(property "License" "Apache-2.0"
			(at 208.28 271.78 0)
			(effects
				(font
					(size 1.27 1.27)
					(thickness 0.15)
				)
				(justify left bottom)
				(hide yes)
			)
		)
		(pin "1"
		)
		(instances
			(project "jetson-orin-baseboard"
				(path ""
					(reference "#PWR0233")
					(unit 1)
				)
			)
		)
	)
	(symbol
		(lib_id "antmicropower:+3V3")
		(at 149.86 232.41 0)
		(unit 1)
		(exclude_from_sim no)
		(in_bom yes)
		(on_board yes)
		(dnp no)
		(property "Reference" "#PWR0230"
			(at 149.86 236.22 0)
			(effects
				(font
					(size 1.27 1.27)
				)
				(justify left bottom)
				(hide yes)
			)
		)
		(property "Value" "+3V3"
			(at 146.685 228.6 0)
			(effects
				(font
					(size 1.27 1.27)
					(thickness 0.15)
				)
				(justify left)
			)
		)
		(property "Footprint" ""
			(at 165.1 240.03 0)
			(effects
				(font
					(size 1.27 1.27)
					(thickness 0.15)
				)
				(justify left bottom)
				(hide yes)
			)
		)
		(property "Datasheet" ""
			(at 165.1 242.57 0)
			(effects
				(font
					(size 1.27 1.27)
					(thickness 0.15)
				)
				(justify left bottom)
				(hide yes)
			)
		)
		(property "Description" ""
			(at 149.86 232.41 0)
			(effects
				(font
					(size 1.27 1.27)
				)
				(hide yes)
			)
		)
		(property "Author" "Antmicro"
			(at 165.1 234.95 0)
			(effects
				(font
					(size 1.27 1.27)
					(thickness 0.15)
				)
				(justify left bottom)
				(hide yes)
			)
		)
		(property "License" "Apache-2.0"
			(at 165.1 237.49 0)
			(effects
				(font
					(size 1.27 1.27)
					(thickness 0.15)
				)
				(justify left bottom)
				(hide yes)
			)
		)
		(pin "1"
		)
		(instances
			(project "jetson-orin-baseboard"
				(path ""
					(reference "#PWR0230")
					(unit 1)
				)
			)
		)
	)
	(symbol
		(lib_id "antmicroResistors0402:R_0R_0402")
		(at 344.17 116.84 0)
		(unit 1)
		(exclude_from_sim no)
		(in_bom no)
		(on_board yes)
		(dnp yes)
		(property "Reference" "R121"
			(at 349.25 116.205 0)
			(effects
				(font
					(size 1.27 1.27)
				)
				(justify left bottom)
			)
		)
		(property "Value" "R_0R_0402"
			(at 364.49 129.54 0)
			(effects
				(font
					(size 1.27 1.27)
					(thickness 0.15)
				)
				(justify left bottom)
				(hide yes)
			)
		)
		(property "Footprint" "antmicro-footprints:R_0402_1005Metric"
			(at 364.49 132.08 0)
			(effects
				(font
					(size 1.27 1.27)
					(thickness 0.15)
				)
				(justify left bottom)
				(hide yes)
			)
		)
		(property "Datasheet" "https://industrial.panasonic.com/cdbs/www-data/pdf/RDA0000/AOA0000C301.pdf"
			(at 364.49 134.62 0)
			(effects
				(font
					(size 1.27 1.27)
					(thickness 0.15)
				)
				(justify left bottom)
				(hide yes)
			)
		)
		(property "Description" ""
			(at 344.17 116.84 0)
			(effects
				(font
					(size 1.27 1.27)
				)
				(hide yes)
			)
		)
		(property "Manufacturer" "Panasonic"
			(at 364.49 139.7 0)
			(effects
				(font
					(size 1.27 1.27)
					(thickness 0.15)
				)
				(justify left bottom)
				(hide yes)
			)
		)
		(property "MPN" "ERJ2GE0R00X"
			(at 364.49 137.16 0)
			(effects
				(font
					(size 1.27 1.27)
					(thickness 0.15)
				)
				(justify left bottom)
				(hide yes)
			)
		)
		(property "Val" "0R"
			(at 341.63 116.205 0)
			(effects
				(font
					(size 1.27 1.27)
					(thickness 0.15)
				)
				(justify left bottom)
			)
		)
		(property "License" "Apache-2.0"
			(at 364.49 142.24 0)
			(effects
				(font
					(size 1.27 1.27)
					(thickness 0.15)
				)
				(justify left bottom)
				(hide yes)
			)
		)
		(property "Author" "Antmicro"
			(at 364.49 144.78 0)
			(effects
				(font
					(size 1.27 1.27)
					(thickness 0.15)
				)
				(justify left bottom)
				(hide yes)
			)
		)
		(property "Tolerance" "~"
			(at 364.49 127 0)
			(effects
				(font
					(size 1.27 1.27)
				)
				(justify left bottom)
				(hide yes)
			)
		)
		(property "Current" "1A"
			(at 364.49 147.32 0)
			(effects
				(font
					(size 1.27 1.27)
					(thickness 0.15)
				)
				(justify left bottom)
				(hide yes)
			)
		)
		(pin "1"
		)
		(pin "2"
		)
		(instances
			(project "jetson-orin-baseboard"
				(path ""
					(reference "R121")
					(unit 1)
				)
			)
		)
	)
	(symbol
		(lib_id "antmicroResistorNetworksArrays:R_4x330R_0402_array")
		(at 199.39 181.61 180)
		(unit 1)
		(exclude_from_sim no)
		(in_bom yes)
		(on_board yes)
		(dnp no)
		(property "Reference" "R101"
			(at 194.31 168.275 0)
			(effects
				(font
					(size 1.27 1.27)
				)
			)
		)
		(property "Value" "R_4x330R_0402_array"
			(at 172.72 176.53 0)
			(effects
				(font
					(size 1.27 1.27)
					(thickness 0.15)
				)
				(justify left bottom)
				(hide yes)
			)
		)
		(property "Footprint" "antmicro-footprints:R_Array_4x0402"
			(at 172.72 171.45 0)
			(effects
				(font
					(size 1.27 1.27)
					(thickness 0.15)
				)
				(justify left bottom)
				(hide yes)
			)
		)
		(property "Datasheet" "http://industrial.panasonic.com/cdbs/www-data/pdf/AOC0000/AOC0000C14.pdf"
			(at 172.72 168.91 0)
			(effects
				(font
					(size 1.27 1.27)
					(thickness 0.15)
				)
				(justify left bottom)
				(hide yes)
			)
		)
		(property "Description" ""
			(at 199.39 181.61 0)
			(effects
				(font
					(size 1.27 1.27)
				)
				(hide yes)
			)
		)
		(property "MPN" "EXB-28V331JX"
			(at 172.72 166.37 0)
			(effects
				(font
					(size 1.27 1.27)
					(thickness 0.15)
				)
				(justify left bottom)
				(hide yes)
			)
		)
		(property "Manufacturer" "Panasonic"
			(at 172.72 163.83 0)
			(effects
				(font
					(size 1.27 1.27)
					(thickness 0.15)
				)
				(justify left bottom)
				(hide yes)
			)
		)
		(property "Author" "Antmicro"
			(at 172.72 161.29 0)
			(effects
				(font
					(size 1.27 1.27)
					(thickness 0.15)
				)
				(justify left bottom)
				(hide yes)
			)
		)
		(property "License" "Apache-2.0"
			(at 172.72 158.75 0)
			(effects
				(font
					(size 1.27 1.27)
					(thickness 0.15)
				)
				(justify left bottom)
				(hide yes)
			)
		)
		(property "Val" "R_4x330R_0402"
			(at 194.31 170.815 0)
			(effects
				(font
					(size 1.27 1.27)
				)
			)
		)
		(pin "1"
		)
		(pin "2"
		)
		(pin "3"
		)
		(pin "4"
		)
		(pin "5"
		)
		(pin "6"
		)
		(pin "7"
		)
		(pin "8"
		)
		(instances
			(project "jetson-orin-baseboard"
				(path ""
					(reference "R101")
					(unit 1)
				)
			)
		)
	)
	(symbol
		(lib_id "antmicroResistors0402:R_0R_0402")
		(at 303.53 114.3 0)
		(unit 1)
		(exclude_from_sim no)
		(in_bom yes)
		(on_board yes)
		(dnp no)
		(property "Reference" "R55"
			(at 308.61 113.665 0)
			(effects
				(font
					(size 1.27 1.27)
				)
				(justify left bottom)
			)
		)
		(property "Value" "R_0R_0402"
			(at 323.85 127 0)
			(effects
				(font
					(size 1.27 1.27)
					(thickness 0.15)
				)
				(justify left bottom)
				(hide yes)
			)
		)
		(property "Footprint" "antmicro-footprints:R_0402_1005Metric"
			(at 323.85 129.54 0)
			(effects
				(font
					(size 1.27 1.27)
					(thickness 0.15)
				)
				(justify left bottom)
				(hide yes)
			)
		)
		(property "Datasheet" "https://industrial.panasonic.com/cdbs/www-data/pdf/RDA0000/AOA0000C301.pdf"
			(at 323.85 132.08 0)
			(effects
				(font
					(size 1.27 1.27)
					(thickness 0.15)
				)
				(justify left bottom)
				(hide yes)
			)
		)
		(property "Description" ""
			(at 303.53 114.3 0)
			(effects
				(font
					(size 1.27 1.27)
				)
				(hide yes)
			)
		)
		(property "Manufacturer" "Panasonic"
			(at 323.85 137.16 0)
			(effects
				(font
					(size 1.27 1.27)
					(thickness 0.15)
				)
				(justify left bottom)
				(hide yes)
			)
		)
		(property "MPN" "ERJ2GE0R00X"
			(at 323.85 134.62 0)
			(effects
				(font
					(size 1.27 1.27)
					(thickness 0.15)
				)
				(justify left bottom)
				(hide yes)
			)
		)
		(property "Val" "0R"
			(at 300.99 113.665 0)
			(effects
				(font
					(size 1.27 1.27)
					(thickness 0.15)
				)
				(justify left bottom)
			)
		)
		(property "License" "Apache-2.0"
			(at 323.85 139.7 0)
			(effects
				(font
					(size 1.27 1.27)
					(thickness 0.15)
				)
				(justify left bottom)
				(hide yes)
			)
		)
		(property "Author" "Antmicro"
			(at 323.85 142.24 0)
			(effects
				(font
					(size 1.27 1.27)
					(thickness 0.15)
				)
				(justify left bottom)
				(hide yes)
			)
		)
		(property "Tolerance" "~"
			(at 323.85 124.46 0)
			(effects
				(font
					(size 1.27 1.27)
				)
				(justify left bottom)
				(hide yes)
			)
		)
		(property "Current" "1A"
			(at 323.85 144.78 0)
			(effects
				(font
					(size 1.27 1.27)
					(thickness 0.15)
				)
				(justify left bottom)
				(hide yes)
			)
		)
		(pin "1"
		)
		(pin "2"
		)
		(instances
			(project "jetson-orin-baseboard"
				(path ""
					(reference "R55")
					(unit 1)
				)
			)
		)
	)
	(symbol
		(lib_id "antmicroPMICPowerDistributionSwitchesLoadDrivers:AP22653_DFN")
		(at 172.72 45.72 0)
		(unit 1)
		(exclude_from_sim no)
		(in_bom yes)
		(on_board yes)
		(dnp no)
		(property "Reference" "U35"
			(at 180.34 39.37 0)
			(effects
				(font
					(size 1.27 1.27)
				)
			)
		)
		(property "Value" "AP22653_DFN"
			(at 203.2 50.8 0)
			(effects
				(font
					(size 1.27 1.27)
					(thickness 0.15)
				)
				(justify left bottom)
				(hide yes)
			)
		)
		(property "Footprint" "antmicro-footprints:DFN-6-1EP_2x2mm_P0.65mm_EP1x1.6mm"
			(at 203.2 53.34 0)
			(effects
				(font
					(size 1.27 1.27)
					(thickness 0.15)
				)
				(justify left bottom)
				(hide yes)
			)
		)
		(property "Datasheet" "https://www.mouser.com/datasheet/2/115/DIOD_S_A0010880137_1-2543666.pdf"
			(at 203.2 55.88 0)
			(effects
				(font
					(size 1.27 1.27)
					(thickness 0.15)
				)
				(justify left bottom)
				(hide yes)
			)
		)
		(property "Description" ""
			(at 172.72 45.72 0)
			(effects
				(font
					(size 1.27 1.27)
				)
				(hide yes)
			)
		)
		(property "MPN" "AP22653FDZ-7"
			(at 180.34 41.91 0)
			(effects
				(font
					(size 1.27 1.27)
					(thickness 0.15)
				)
			)
		)
		(property "Manufacturer" "Diodes Incorporated"
			(at 203.2 60.96 0)
			(effects
				(font
					(size 1.27 1.27)
					(thickness 0.15)
				)
				(justify left bottom)
				(hide yes)
			)
		)
		(property "Author" "Antmicro"
			(at 203.2 63.5 0)
			(effects
				(font
					(size 1.27 1.27)
					(thickness 0.15)
				)
				(justify left bottom)
				(hide yes)
			)
		)
		(property "License" "Apache-2.0"
			(at 203.2 66.04 0)
			(effects
				(font
					(size 1.27 1.27)
					(thickness 0.15)
				)
				(justify left bottom)
				(hide yes)
			)
		)
		(pin "1"
		)
		(pin "2"
		)
		(pin "3"
		)
		(pin "4"
		)
		(pin "5"
		)
		(pin "6"
		)
		(pin "7"
		)
		(instances
			(project "jetson-orin-baseboard"
				(path ""
					(reference "U35")
					(unit 1)
				)
			)
		)
	)
	(symbol
		(lib_id "antmicropower:GND")
		(at 317.5 137.16 0)
		(unit 1)
		(exclude_from_sim no)
		(in_bom yes)
		(on_board yes)
		(dnp no)
		(fields_autoplaced yes)
		(property "Reference" "#PWR0239"
			(at 317.5 143.51 0)
			(effects
				(font
					(size 1.27 1.27)
				)
				(justify left bottom)
				(hide yes)
			)
		)
		(property "Value" "GND"
			(at 317.5 140.97 0)
			(effects
				(font
					(size 1.27 1.27)
					(thickness 0.15)
				)
			)
		)
		(property "Footprint" ""
			(at 326.39 144.78 0)
			(effects
				(font
					(size 1.27 1.27)
					(thickness 0.15)
				)
				(justify left bottom)
				(hide yes)
			)
		)
		(property "Datasheet" ""
			(at 326.39 149.86 0)
			(effects
				(font
					(size 1.27 1.27)
					(thickness 0.15)
				)
				(justify left bottom)
				(hide yes)
			)
		)
		(property "Description" ""
			(at 317.5 137.16 0)
			(effects
				(font
					(size 1.27 1.27)
				)
				(hide yes)
			)
		)
		(property "Author" "Antmicro"
			(at 326.39 144.78 0)
			(effects
				(font
					(size 1.27 1.27)
					(thickness 0.15)
				)
				(justify left bottom)
				(hide yes)
			)
		)
		(property "License" "Apache-2.0"
			(at 326.39 147.32 0)
			(effects
				(font
					(size 1.27 1.27)
					(thickness 0.15)
				)
				(justify left bottom)
				(hide yes)
			)
		)
		(pin "1"
		)
		(instances
			(project "jetson-orin-baseboard"
				(path ""
					(reference "#PWR0239")
					(unit 1)
				)
			)
		)
	)
	(symbol
		(lib_id "antmicroResistors0402:R_15k_0402")
		(at 194.31 54.61 90)
		(unit 1)
		(exclude_from_sim no)
		(in_bom yes)
		(on_board yes)
		(dnp no)
		(property "Reference" "R190"
			(at 195.58 50.8 90)
			(effects
				(font
					(size 1.27 1.27)
				)
				(justify right)
			)
		)
		(property "Value" "R_15k_0402"
			(at 207.01 34.29 0)
			(effects
				(font
					(size 1.27 1.27)
					(thickness 0.15)
				)
				(justify left bottom)
				(hide yes)
			)
		)
		(property "Footprint" "antmicro-footprints:R_0402_1005Metric"
			(at 209.55 34.29 0)
			(effects
				(font
					(size 1.27 1.27)
					(thickness 0.15)
				)
				(justify left bottom)
				(hide yes)
			)
		)
		(property "Datasheet" "https://www.bourns.com/docs/product-datasheets/cr.pdf"
			(at 212.09 34.29 0)
			(effects
				(font
					(size 1.27 1.27)
					(thickness 0.15)
				)
				(justify left bottom)
				(hide yes)
			)
		)
		(property "Description" ""
			(at 194.31 54.61 0)
			(effects
				(font
					(size 1.27 1.27)
				)
				(hide yes)
			)
		)
		(property "Manufacturer" "Bourns"
			(at 217.17 34.29 0)
			(effects
				(font
					(size 1.27 1.27)
					(thickness 0.15)
				)
				(justify left bottom)
				(hide yes)
			)
		)
		(property "MPN" "CR0402-FX-1502GLF"
			(at 214.63 34.29 0)
			(effects
				(font
					(size 1.27 1.27)
					(thickness 0.15)
				)
				(justify left bottom)
				(hide yes)
			)
		)
		(property "Val" "15k"
			(at 195.58 53.34 90)
			(effects
				(font
					(size 1.27 1.27)
					(thickness 0.15)
				)
				(justify right)
			)
		)
		(property "License" "Apache-2.0"
			(at 219.71 34.29 0)
			(effects
				(font
					(size 1.27 1.27)
					(thickness 0.15)
				)
				(justify left bottom)
				(hide yes)
			)
		)
		(property "Author" "Antmicro"
			(at 222.25 34.29 0)
			(effects
				(font
					(size 1.27 1.27)
					(thickness 0.15)
				)
				(justify left bottom)
				(hide yes)
			)
		)
		(property "Tolerance" "1%"
			(at 204.47 34.29 0)
			(effects
				(font
					(size 1.27 1.27)
				)
				(justify left bottom)
				(hide yes)
			)
		)
		(pin "1"
		)
		(pin "2"
		)
		(instances
			(project "jetson-orin-baseboard"
				(path ""
					(reference "R190")
					(unit 1)
				)
			)
		)
	)
	(symbol
		(lib_id "antmicropower:GND")
		(at 44.45 247.65 0)
		(unit 1)
		(exclude_from_sim no)
		(in_bom yes)
		(on_board yes)
		(dnp no)
		(fields_autoplaced yes)
		(property "Reference" "#PWR0214"
			(at 44.45 254 0)
			(effects
				(font
					(size 1.27 1.27)
				)
				(justify left bottom)
				(hide yes)
			)
		)
		(property "Value" "GND"
			(at 44.45 251.46 0)
			(effects
				(font
					(size 1.27 1.27)
					(thickness 0.15)
				)
			)
		)
		(property "Footprint" ""
			(at 53.34 255.27 0)
			(effects
				(font
					(size 1.27 1.27)
					(thickness 0.15)
				)
				(justify left bottom)
				(hide yes)
			)
		)
		(property "Datasheet" ""
			(at 53.34 260.35 0)
			(effects
				(font
					(size 1.27 1.27)
					(thickness 0.15)
				)
				(justify left bottom)
				(hide yes)
			)
		)
		(property "Description" ""
			(at 44.45 247.65 0)
			(effects
				(font
					(size 1.27 1.27)
				)
				(hide yes)
			)
		)
		(property "Author" "Antmicro"
			(at 53.34 255.27 0)
			(effects
				(font
					(size 1.27 1.27)
					(thickness 0.15)
				)
				(justify left bottom)
				(hide yes)
			)
		)
		(property "License" "Apache-2.0"
			(at 53.34 257.81 0)
			(effects
				(font
					(size 1.27 1.27)
					(thickness 0.15)
				)
				(justify left bottom)
				(hide yes)
			)
		)
		(pin "1"
		)
		(instances
			(project "jetson-orin-baseboard"
				(path ""
					(reference "#PWR0214")
					(unit 1)
				)
			)
		)
	)
	(symbol
		(lib_id "antmicroCapacitors0402:C_1u_0402")
		(at 312.42 180.34 90)
		(mirror x)
		(unit 1)
		(exclude_from_sim no)
		(in_bom yes)
		(on_board yes)
		(dnp no)
		(property "Reference" "C114"
			(at 314.325 181.61 90)
			(effects
				(font
					(size 1.27 1.27)
				)
				(justify right)
			)
		)
		(property "Value" "C_1u_0402"
			(at 322.58 200.66 0)
			(effects
				(font
					(size 1.27 1.27)
					(thickness 0.15)
				)
				(justify left bottom)
				(hide yes)
			)
		)
		(property "Footprint" "antmicro-footprints:C_0402_1005Metric"
			(at 325.12 200.66 0)
			(effects
				(font
					(size 1.27 1.27)
					(thickness 0.15)
				)
				(justify left bottom)
				(hide yes)
			)
		)
		(property "Datasheet" "https://product.tdk.com/en/search/capacitor/ceramic/mlcc/info?part_no=C1005X6S1A105K050BC"
			(at 327.66 200.66 0)
			(effects
				(font
					(size 1.27 1.27)
					(thickness 0.15)
				)
				(justify left bottom)
				(hide yes)
			)
		)
		(property "Description" ""
			(at 312.42 180.34 0)
			(effects
				(font
					(size 1.27 1.27)
				)
				(hide yes)
			)
		)
		(property "Manufacturer" "TDK"
			(at 332.74 200.66 0)
			(effects
				(font
					(size 1.27 1.27)
					(thickness 0.15)
				)
				(justify left bottom)
				(hide yes)
			)
		)
		(property "MPN" "C1005X6S1A105K050BC"
			(at 330.2 200.66 0)
			(effects
				(font
					(size 1.27 1.27)
					(thickness 0.15)
				)
				(justify left bottom)
				(hide yes)
			)
		)
		(property "Val" "1u"
			(at 314.325 184.15 90)
			(effects
				(font
					(size 1.27 1.27)
					(thickness 0.15)
				)
				(justify right)
			)
		)
		(property "License" "Apache-2.0"
			(at 335.28 200.66 0)
			(effects
				(font
					(size 1.27 1.27)
					(thickness 0.15)
				)
				(justify left bottom)
				(hide yes)
			)
		)
		(property "Author" "Antmicro"
			(at 337.82 200.66 0)
			(effects
				(font
					(size 1.27 1.27)
					(thickness 0.15)
				)
				(justify left bottom)
				(hide yes)
			)
		)
		(property "Voltage" ""
			(at 340.36 200.66 0)
			(effects
				(font
					(size 1.27 1.27)
				)
				(justify left bottom)
				(hide yes)
			)
		)
		(property "Dielectric" ""
			(at 342.9 200.66 0)
			(effects
				(font
					(size 1.27 1.27)
				)
				(justify left bottom)
				(hide yes)
			)
		)
		(pin "1"
		)
		(pin "2"
		)
		(instances
			(project "jetson-orin-baseboard"
				(path ""
					(reference "C114")
					(unit 1)
				)
			)
		)
	)
	(symbol
		(lib_id "antmicroResistors0402:R_100k_0402")
		(at 199.39 260.35 90)
		(unit 1)
		(exclude_from_sim no)
		(in_bom yes)
		(on_board yes)
		(dnp no)
		(property "Reference" "R230"
			(at 198.12 256.54 90)
			(effects
				(font
					(size 1.27 1.27)
				)
				(justify left)
			)
		)
		(property "Value" "R_100k_0402"
			(at 212.09 240.03 0)
			(effects
				(font
					(size 1.27 1.27)
					(thickness 0.15)
				)
				(justify left bottom)
				(hide yes)
			)
		)
		(property "Footprint" "antmicro-footprints:R_0402_1005Metric"
			(at 214.63 240.03 0)
			(effects
				(font
					(size 1.27 1.27)
					(thickness 0.15)
				)
				(justify left bottom)
				(hide yes)
			)
		)
		(property "Datasheet" "https://www.bourns.com/docs/product-datasheets/cr.pdf"
			(at 217.17 240.03 0)
			(effects
				(font
					(size 1.27 1.27)
					(thickness 0.15)
				)
				(justify left bottom)
				(hide yes)
			)
		)
		(property "Description" ""
			(at 199.39 260.35 0)
			(effects
				(font
					(size 1.27 1.27)
				)
				(hide yes)
			)
		)
		(property "Manufacturer" "Bourns"
			(at 222.25 240.03 0)
			(effects
				(font
					(size 1.27 1.27)
					(thickness 0.15)
				)
				(justify left bottom)
				(hide yes)
			)
		)
		(property "MPN" "CR0402-FX-1003GLF"
			(at 219.71 240.03 0)
			(effects
				(font
					(size 1.27 1.27)
					(thickness 0.15)
				)
				(justify left bottom)
				(hide yes)
			)
		)
		(property "Val" "100k"
			(at 198.12 259.08 90)
			(effects
				(font
					(size 1.27 1.27)
					(thickness 0.15)
				)
				(justify left)
			)
		)
		(property "License" "Apache-2.0"
			(at 224.79 240.03 0)
			(effects
				(font
					(size 1.27 1.27)
					(thickness 0.15)
				)
				(justify left bottom)
				(hide yes)
			)
		)
		(property "Author" "Antmicro"
			(at 227.33 240.03 0)
			(effects
				(font
					(size 1.27 1.27)
					(thickness 0.15)
				)
				(justify left bottom)
				(hide yes)
			)
		)
		(property "Tolerance" "1%"
			(at 209.55 240.03 0)
			(effects
				(font
					(size 1.27 1.27)
				)
				(justify left bottom)
				(hide yes)
			)
		)
		(pin "1"
		)
		(pin "2"
		)
		(instances
			(project "jetson-orin-baseboard"
				(path ""
					(reference "R230")
					(unit 1)
				)
			)
		)
	)
	(symbol
		(lib_id "antmicroResistors0603:R_0R_22.4A_0603")
		(at 246.38 168.91 270)
		(unit 1)
		(exclude_from_sim no)
		(in_bom yes)
		(on_board yes)
		(dnp no)
		(property "Reference" "R248"
			(at 247.65 170.18 90)
			(effects
				(font
					(size 1.27 1.27)
				)
				(justify left)
			)
		)
		(property "Value" "R_0R_22.4A_0603"
			(at 237.49 171.45 0)
			(effects
				(font
					(size 1.27 1.27)
					(thickness 0.15)
				)
				(hide yes)
			)
		)
		(property "Footprint" "antmicro-footprints:R_0603_1608Metric"
			(at 236.22 184.15 0)
			(effects
				(font
					(size 1.27 1.27)
					(thickness 0.15)
				)
				(justify left bottom)
				(hide yes)
			)
		)
		(property "Datasheet" "https://fscdn.rohm.com/en/products/databook/datasheet/passive/resistor/chip_resistor/pmr-jpw-e.pdf"
			(at 233.68 184.15 0)
			(effects
				(font
					(size 1.27 1.27)
					(thickness 0.15)
				)
				(justify left bottom)
				(hide yes)
			)
		)
		(property "Description" ""
			(at 246.38 168.91 0)
			(effects
				(font
					(size 1.27 1.27)
				)
				(hide yes)
			)
		)
		(property "Manufacturer" "ROHM Semiconductor"
			(at 228.6 184.15 0)
			(effects
				(font
					(size 1.27 1.27)
					(thickness 0.15)
				)
				(justify left bottom)
				(hide yes)
			)
		)
		(property "MPN" "PMR03EZPJ000"
			(at 231.14 184.15 0)
			(effects
				(font
					(size 1.27 1.27)
					(thickness 0.15)
				)
				(justify left bottom)
				(hide yes)
			)
		)
		(property "Val" "0R"
			(at 247.65 172.72 90)
			(effects
				(font
					(size 1.27 1.27)
					(thickness 0.15)
				)
				(justify left)
			)
		)
		(property "Author" "Antmicro"
			(at 223.52 184.15 0)
			(effects
				(font
					(size 1.27 1.27)
					(thickness 0.15)
				)
				(justify left bottom)
				(hide yes)
			)
		)
		(property "License" "Apache-2.0"
			(at 220.98 184.15 0)
			(effects
				(font
					(size 1.27 1.27)
					(thickness 0.15)
				)
				(justify left bottom)
				(hide yes)
			)
		)
		(property "Max. Curr." "22.4A"
			(at 244.475 168.275 0)
			(effects
				(font
					(size 1.27 1.27)
					(thickness 0.15)
				)
				(justify left)
			)
		)
		(property "Tolerance" "template_tolerance"
			(at 236.22 189.23 0)
			(effects
				(font
					(size 1.27 1.27)
				)
				(justify left bottom)
				(hide yes)
			)
		)
		(pin "1"
		)
		(pin "2"
		)
		(instances
			(project "jetson-orin-baseboard"
				(path ""
					(reference "R248")
					(unit 1)
				)
			)
		)
	)
	(symbol
		(lib_id "antmicroResistors0402:R_470R_0402")
		(at 349.25 119.38 180)
		(unit 1)
		(exclude_from_sim no)
		(in_bom yes)
		(on_board yes)
		(dnp no)
		(property "Reference" "R335"
			(at 349.25 118.745 0)
			(effects
				(font
					(size 1.27 1.27)
				)
				(justify right top)
			)
		)
		(property "Value" "R_470R_0402"
			(at 328.93 106.68 0)
			(effects
				(font
					(size 1.27 1.27)
					(thickness 0.15)
				)
				(justify left bottom)
				(hide yes)
			)
		)
		(property "Footprint" "antmicro-footprints:R_0402_1005Metric"
			(at 328.93 104.14 0)
			(effects
				(font
					(size 1.27 1.27)
					(thickness 0.15)
				)
				(justify left bottom)
				(hide yes)
			)
		)
		(property "Datasheet" "https://www.bourns.com/docs/product-datasheets/cr.pdf"
			(at 328.93 101.6 0)
			(effects
				(font
					(size 1.27 1.27)
					(thickness 0.15)
				)
				(justify left bottom)
				(hide yes)
			)
		)
		(property "Description" ""
			(at 349.25 119.38 0)
			(effects
				(font
					(size 1.27 1.27)
				)
				(hide yes)
			)
		)
		(property "Manufacturer" "Bourns"
			(at 328.93 96.52 0)
			(effects
				(font
					(size 1.27 1.27)
					(thickness 0.15)
				)
				(justify left bottom)
				(hide yes)
			)
		)
		(property "MPN" "CR0402-FX-4700GLF"
			(at 328.93 99.06 0)
			(effects
				(font
					(size 1.27 1.27)
					(thickness 0.15)
				)
				(justify left bottom)
				(hide yes)
			)
		)
		(property "Val" "470R"
			(at 339.09 118.745 0)
			(effects
				(font
					(size 1.27 1.27)
					(thickness 0.15)
				)
				(justify right top)
			)
		)
		(property "License" "Apache-2.0"
			(at 328.93 93.98 0)
			(effects
				(font
					(size 1.27 1.27)
					(thickness 0.15)
				)
				(justify left bottom)
				(hide yes)
			)
		)
		(property "Author" "Antmicro"
			(at 328.93 91.44 0)
			(effects
				(font
					(size 1.27 1.27)
					(thickness 0.15)
				)
				(justify left bottom)
				(hide yes)
			)
		)
		(property "Tolerance" "1%"
			(at 328.93 109.22 0)
			(effects
				(font
					(size 1.27 1.27)
				)
				(justify left bottom)
				(hide yes)
			)
		)
		(pin "1"
		)
		(pin "2"
		)
		(instances
			(project "jetson-orin-baseboard"
				(path ""
					(reference "R335")
					(unit 1)
				)
			)
		)
	)
	(symbol
		(lib_id "antmicroCapacitors0402:C_1u_0402")
		(at 246.38 180.34 90)
		(mirror x)
		(unit 1)
		(exclude_from_sim no)
		(in_bom yes)
		(on_board yes)
		(dnp no)
		(property "Reference" "C115"
			(at 248.285 181.61 90)
			(effects
				(font
					(size 1.27 1.27)
				)
				(justify right)
			)
		)
		(property "Value" "C_1u_0402"
			(at 256.54 200.66 0)
			(effects
				(font
					(size 1.27 1.27)
					(thickness 0.15)
				)
				(justify left bottom)
				(hide yes)
			)
		)
		(property "Footprint" "antmicro-footprints:C_0402_1005Metric"
			(at 259.08 200.66 0)
			(effects
				(font
					(size 1.27 1.27)
					(thickness 0.15)
				)
				(justify left bottom)
				(hide yes)
			)
		)
		(property "Datasheet" "https://product.tdk.com/en/search/capacitor/ceramic/mlcc/info?part_no=C1005X6S1A105K050BC"
			(at 261.62 200.66 0)
			(effects
				(font
					(size 1.27 1.27)
					(thickness 0.15)
				)
				(justify left bottom)
				(hide yes)
			)
		)
		(property "Description" ""
			(at 246.38 180.34 0)
			(effects
				(font
					(size 1.27 1.27)
				)
				(hide yes)
			)
		)
		(property "Manufacturer" "TDK"
			(at 266.7 200.66 0)
			(effects
				(font
					(size 1.27 1.27)
					(thickness 0.15)
				)
				(justify left bottom)
				(hide yes)
			)
		)
		(property "MPN" "C1005X6S1A105K050BC"
			(at 264.16 200.66 0)
			(effects
				(font
					(size 1.27 1.27)
					(thickness 0.15)
				)
				(justify left bottom)
				(hide yes)
			)
		)
		(property "Val" "1u"
			(at 248.285 184.15 90)
			(effects
				(font
					(size 1.27 1.27)
					(thickness 0.15)
				)
				(justify right)
			)
		)
		(property "License" "Apache-2.0"
			(at 269.24 200.66 0)
			(effects
				(font
					(size 1.27 1.27)
					(thickness 0.15)
				)
				(justify left bottom)
				(hide yes)
			)
		)
		(property "Author" "Antmicro"
			(at 271.78 200.66 0)
			(effects
				(font
					(size 1.27 1.27)
					(thickness 0.15)
				)
				(justify left bottom)
				(hide yes)
			)
		)
		(property "Voltage" ""
			(at 274.32 200.66 0)
			(effects
				(font
					(size 1.27 1.27)
				)
				(justify left bottom)
				(hide yes)
			)
		)
		(property "Dielectric" ""
			(at 276.86 200.66 0)
			(effects
				(font
					(size 1.27 1.27)
				)
				(justify left bottom)
				(hide yes)
			)
		)
		(pin "1"
		)
		(pin "2"
		)
		(instances
			(project "jetson-orin-baseboard"
				(path ""
					(reference "C115")
					(unit 1)
				)
			)
		)
	)
	(symbol
		(lib_id "antmicroResistors0402:R_10k_0402")
		(at 162.56 40.64 90)
		(unit 1)
		(exclude_from_sim no)
		(in_bom yes)
		(on_board yes)
		(dnp no)
		(property "Reference" "R189"
			(at 163.83 36.83 90)
			(effects
				(font
					(size 1.27 1.27)
				)
				(justify right)
			)
		)
		(property "Value" "R_10k_0402"
			(at 175.26 20.32 0)
			(effects
				(font
					(size 1.27 1.27)
					(thickness 0.15)
				)
				(justify left bottom)
				(hide yes)
			)
		)
		(property "Footprint" "antmicro-footprints:R_0402_1005Metric"
			(at 177.8 20.32 0)
			(effects
				(font
					(size 1.27 1.27)
					(thickness 0.15)
				)
				(justify left bottom)
				(hide yes)
			)
		)
		(property "Datasheet" "https://www.bourns.com/docs/product-datasheets/cr.pdf"
			(at 180.34 20.32 0)
			(effects
				(font
					(size 1.27 1.27)
					(thickness 0.15)
				)
				(justify left bottom)
				(hide yes)
			)
		)
		(property "Description" ""
			(at 162.56 40.64 0)
			(effects
				(font
					(size 1.27 1.27)
				)
				(hide yes)
			)
		)
		(property "Manufacturer" "Bourns"
			(at 185.42 20.32 0)
			(effects
				(font
					(size 1.27 1.27)
					(thickness 0.15)
				)
				(justify left bottom)
				(hide yes)
			)
		)
		(property "MPN" "CR0402-FX-1002GLF"
			(at 182.88 20.32 0)
			(effects
				(font
					(size 1.27 1.27)
					(thickness 0.15)
				)
				(justify left bottom)
				(hide yes)
			)
		)
		(property "Val" "10k"
			(at 163.83 39.37 90)
			(effects
				(font
					(size 1.27 1.27)
					(thickness 0.15)
				)
				(justify right)
			)
		)
		(property "License" "Apache-2.0"
			(at 187.96 20.32 0)
			(effects
				(font
					(size 1.27 1.27)
					(thickness 0.15)
				)
				(justify left bottom)
				(hide yes)
			)
		)
		(property "Author" "Antmicro"
			(at 190.5 20.32 0)
			(effects
				(font
					(size 1.27 1.27)
					(thickness 0.15)
				)
				(justify left bottom)
				(hide yes)
			)
		)
		(property "Tolerance" "1%"
			(at 172.72 20.32 0)
			(effects
				(font
					(size 1.27 1.27)
				)
				(justify left bottom)
				(hide yes)
			)
		)
		(pin "1"
		)
		(pin "2"
		)
		(instances
			(project "jetson-orin-baseboard"
				(path ""
					(reference "R189")
					(unit 1)
				)
			)
		)
	)
	(symbol
		(lib_id "antmicroTVSDiodes:TPD1E0B04_XDFN-2")
		(at 388.62 238.76 0)
		(unit 1)
		(exclude_from_sim no)
		(in_bom yes)
		(on_board yes)
		(dnp no)
		(property "Reference" "D19"
			(at 393.065 238.125 0)
			(effects
				(font
					(size 1.27 1.27)
				)
				(justify left bottom)
			)
		)
		(property "Value" "TPD1E0B04_XDFN-2"
			(at 403.86 248.92 0)
			(effects
				(font
					(size 1.27 1.27)
					(thickness 0.15)
				)
				(justify left bottom)
				(hide yes)
			)
		)
		(property "Footprint" "antmicro-footprints:XDFN-2_1x0.60mm"
			(at 403.86 243.84 0)
			(effects
				(font
					(size 1.27 1.27)
					(thickness 0.15)
				)
				(justify left bottom)
				(hide yes)
			)
		)
		(property "Datasheet" "https://www.ti.com/general/docs/suppproductinfo.tsp?distId=26&gotoUrl=https://www.ti.com/lit/gpn/tpd1e0b04"
			(at 403.86 246.38 0)
			(effects
				(font
					(size 1.27 1.27)
					(thickness 0.15)
				)
				(justify left bottom)
				(hide yes)
			)
		)
		(property "Description" ""
			(at 388.62 238.76 0)
			(effects
				(font
					(size 1.27 1.27)
				)
				(hide yes)
			)
		)
		(property "Manufacturer" "Texas Instruments"
			(at 403.86 251.46 0)
			(effects
				(font
					(size 1.27 1.27)
					(thickness 0.15)
				)
				(justify left bottom)
				(hide yes)
			)
		)
		(property "MPN" "TPD1E0B04DPYR"
			(at 373.38 238.125 0)
			(effects
				(font
					(size 1.27 1.27)
					(thickness 0.15)
				)
				(justify left bottom)
			)
		)
		(property "Author" "Antmicro"
			(at 403.86 254 0)
			(effects
				(font
					(size 1.27 1.27)
					(thickness 0.15)
				)
				(justify left bottom)
				(hide yes)
			)
		)
		(property "License" "Apache-2.0"
			(at 403.86 256.54 0)
			(effects
				(font
					(size 1.27 1.27)
					(thickness 0.15)
				)
				(justify left bottom)
				(hide yes)
			)
		)
		(pin "1"
		)
		(pin "2"
		)
		(instances
			(project "jetson-orin-baseboard"
				(path ""
					(reference "D19")
					(unit 1)
				)
			)
		)
	)
	(symbol
		(lib_id "antmicroResistors0402:R_10k_0402")
		(at 261.62 260.35 90)
		(unit 1)
		(exclude_from_sim no)
		(in_bom yes)
		(on_board yes)
		(dnp no)
		(fields_autoplaced yes)
		(property "Reference" "R242"
			(at 263.652 256.54 90)
			(effects
				(font
					(size 1.27 1.27)
				)
				(justify right)
			)
		)
		(property "Value" "R_10k_0402"
			(at 274.32 240.03 0)
			(effects
				(font
					(size 1.27 1.27)
					(thickness 0.15)
				)
				(justify left bottom)
				(hide yes)
			)
		)
		(property "Footprint" "antmicro-footprints:R_0402_1005Metric"
			(at 276.86 240.03 0)
			(effects
				(font
					(size 1.27 1.27)
					(thickness 0.15)
				)
				(justify left bottom)
				(hide yes)
			)
		)
		(property "Datasheet" "https://www.bourns.com/docs/product-datasheets/cr.pdf"
			(at 279.4 240.03 0)
			(effects
				(font
					(size 1.27 1.27)
					(thickness 0.15)
				)
				(justify left bottom)
				(hide yes)
			)
		)
		(property "Description" ""
			(at 261.62 260.35 0)
			(effects
				(font
					(size 1.27 1.27)
				)
				(hide yes)
			)
		)
		(property "Manufacturer" "Bourns"
			(at 284.48 240.03 0)
			(effects
				(font
					(size 1.27 1.27)
					(thickness 0.15)
				)
				(justify left bottom)
				(hide yes)
			)
		)
		(property "MPN" "CR0402-FX-1002GLF"
			(at 281.94 240.03 0)
			(effects
				(font
					(size 1.27 1.27)
					(thickness 0.15)
				)
				(justify left bottom)
				(hide yes)
			)
		)
		(property "Val" "10k"
			(at 263.652 259.08 90)
			(effects
				(font
					(size 1.27 1.27)
					(thickness 0.15)
				)
				(justify right)
			)
		)
		(property "License" "Apache-2.0"
			(at 287.02 240.03 0)
			(effects
				(font
					(size 1.27 1.27)
					(thickness 0.15)
				)
				(justify left bottom)
				(hide yes)
			)
		)
		(property "Author" "Antmicro"
			(at 289.56 240.03 0)
			(effects
				(font
					(size 1.27 1.27)
					(thickness 0.15)
				)
				(justify left bottom)
				(hide yes)
			)
		)
		(property "Tolerance" "1%"
			(at 271.78 240.03 0)
			(effects
				(font
					(size 1.27 1.27)
				)
				(justify left bottom)
				(hide yes)
			)
		)
		(pin "1"
		)
		(pin "2"
		)
		(instances
			(project "jetson-orin-baseboard"
				(path ""
					(reference "R242")
					(unit 1)
				)
			)
		)
	)
	(symbol
		(lib_id "antmicroResistorNetworksArrays:R_4x0R_0201_array")
		(at 113.03 71.12 0)
		(mirror y)
		(unit 1)
		(exclude_from_sim no)
		(in_bom yes)
		(on_board yes)
		(dnp no)
		(property "Reference" "R195"
			(at 107.95 81.915 0)
			(effects
				(font
					(size 1.27 1.27)
				)
			)
		)
		(property "Value" "R_4x0R_0201_array"
			(at 86.36 78.74 0)
			(effects
				(font
					(size 1.27 1.27)
					(thickness 0.15)
				)
				(justify left bottom)
				(hide yes)
			)
		)
		(property "Footprint" "antmicro-footprints:R_Array_4x0201_Panasonic_EXB18V"
			(at 86.36 83.82 0)
			(effects
				(font
					(size 1.27 1.27)
					(thickness 0.15)
				)
				(justify left bottom)
				(hide yes)
			)
		)
		(property "Datasheet" "http://industrial.panasonic.com/cdbs/www-data/pdf/AOC0000/AOC0000C14.pdf"
			(at 86.36 86.36 0)
			(effects
				(font
					(size 1.27 1.27)
					(thickness 0.15)
				)
				(justify left bottom)
				(hide yes)
			)
		)
		(property "Description" ""
			(at 113.03 71.12 0)
			(effects
				(font
					(size 1.27 1.27)
				)
				(hide yes)
			)
		)
		(property "MPN" "EXB-18VR000X"
			(at 86.36 88.9 0)
			(effects
				(font
					(size 1.27 1.27)
					(thickness 0.15)
				)
				(justify left bottom)
				(hide yes)
			)
		)
		(property "Manufacturer" "Panasonic"
			(at 86.36 91.44 0)
			(effects
				(font
					(size 1.27 1.27)
					(thickness 0.15)
				)
				(justify left bottom)
				(hide yes)
			)
		)
		(property "Val" "4x0R_0201"
			(at 107.95 84.455 0)
			(effects
				(font
					(size 1.27 1.27)
					(thickness 0.15)
				)
			)
		)
		(property "Author" "Antmicro"
			(at 86.36 93.98 0)
			(effects
				(font
					(size 1.27 1.27)
					(thickness 0.15)
				)
				(justify left bottom)
				(hide yes)
			)
		)
		(property "License" "Apache-2.0"
			(at 86.36 96.52 0)
			(effects
				(font
					(size 1.27 1.27)
					(thickness 0.15)
				)
				(justify left bottom)
				(hide yes)
			)
		)
		(pin "1"
		)
		(pin "2"
		)
		(pin "3"
		)
		(pin "4"
		)
		(pin "5"
		)
		(pin "6"
		)
		(pin "7"
		)
		(pin "8"
		)
		(instances
			(project "jetson-orin-baseboard"
				(path ""
					(reference "R195")
					(unit 1)
				)
			)
		)
	)
	(symbol
		(lib_id "antmicroTVSDiodes:TPD1E0B04_XDFN-2")
		(at 388.62 162.56 0)
		(unit 1)
		(exclude_from_sim no)
		(in_bom yes)
		(on_board yes)
		(dnp no)
		(property "Reference" "D23"
			(at 393.065 161.925 0)
			(effects
				(font
					(size 1.27 1.27)
				)
				(justify left bottom)
			)
		)
		(property "Value" "TPD1E0B04_XDFN-2"
			(at 403.86 172.72 0)
			(effects
				(font
					(size 1.27 1.27)
					(thickness 0.15)
				)
				(justify left bottom)
				(hide yes)
			)
		)
		(property "Footprint" "antmicro-footprints:XDFN-2_1x0.60mm"
			(at 403.86 167.64 0)
			(effects
				(font
					(size 1.27 1.27)
					(thickness 0.15)
				)
				(justify left bottom)
				(hide yes)
			)
		)
		(property "Datasheet" "https://www.ti.com/general/docs/suppproductinfo.tsp?distId=26&gotoUrl=https://www.ti.com/lit/gpn/tpd1e0b04"
			(at 403.86 170.18 0)
			(effects
				(font
					(size 1.27 1.27)
					(thickness 0.15)
				)
				(justify left bottom)
				(hide yes)
			)
		)
		(property "Description" ""
			(at 388.62 162.56 0)
			(effects
				(font
					(size 1.27 1.27)
				)
				(hide yes)
			)
		)
		(property "Manufacturer" "Texas Instruments"
			(at 403.86 175.26 0)
			(effects
				(font
					(size 1.27 1.27)
					(thickness 0.15)
				)
				(justify left bottom)
				(hide yes)
			)
		)
		(property "MPN" "TPD1E0B04DPYR"
			(at 373.38 161.925 0)
			(effects
				(font
					(size 1.27 1.27)
					(thickness 0.15)
				)
				(justify left bottom)
			)
		)
		(property "Author" "Antmicro"
			(at 403.86 177.8 0)
			(effects
				(font
					(size 1.27 1.27)
					(thickness 0.15)
				)
				(justify left bottom)
				(hide yes)
			)
		)
		(property "License" "Apache-2.0"
			(at 403.86 180.34 0)
			(effects
				(font
					(size 1.27 1.27)
					(thickness 0.15)
				)
				(justify left bottom)
				(hide yes)
			)
		)
		(pin "1"
		)
		(pin "2"
		)
		(instances
			(project "jetson-orin-baseboard"
				(path ""
					(reference "D23")
					(unit 1)
				)
			)
		)
	)
	(symbol
		(lib_id "antmicropower:GND")
		(at 330.2 246.38 0)
		(unit 1)
		(exclude_from_sim no)
		(in_bom yes)
		(on_board yes)
		(dnp no)
		(fields_autoplaced yes)
		(property "Reference" "#PWR011"
			(at 330.2 252.73 0)
			(effects
				(font
					(size 1.27 1.27)
				)
				(justify left bottom)
				(hide yes)
			)
		)
		(property "Value" "GND"
			(at 330.2 250.19 0)
			(effects
				(font
					(size 1.27 1.27)
					(thickness 0.15)
				)
			)
		)
		(property "Footprint" ""
			(at 339.09 254 0)
			(effects
				(font
					(size 1.27 1.27)
					(thickness 0.15)
				)
				(justify left bottom)
				(hide yes)
			)
		)
		(property "Datasheet" ""
			(at 339.09 259.08 0)
			(effects
				(font
					(size 1.27 1.27)
					(thickness 0.15)
				)
				(justify left bottom)
				(hide yes)
			)
		)
		(property "Description" ""
			(at 330.2 246.38 0)
			(effects
				(font
					(size 1.27 1.27)
				)
				(hide yes)
			)
		)
		(property "Author" "Antmicro"
			(at 339.09 254 0)
			(effects
				(font
					(size 1.27 1.27)
					(thickness 0.15)
				)
				(justify left bottom)
				(hide yes)
			)
		)
		(property "License" "Apache-2.0"
			(at 339.09 256.54 0)
			(effects
				(font
					(size 1.27 1.27)
					(thickness 0.15)
				)
				(justify left bottom)
				(hide yes)
			)
		)
		(pin "1"
		)
		(instances
			(project "jetson-orin-baseboard"
				(path ""
					(reference "#PWR011")
					(unit 1)
				)
			)
		)
	)
	(symbol
		(lib_id "antmicropower:GND")
		(at 295.91 186.69 0)
		(unit 1)
		(exclude_from_sim no)
		(in_bom yes)
		(on_board yes)
		(dnp no)
		(fields_autoplaced yes)
		(property "Reference" "#PWR0244"
			(at 295.91 193.04 0)
			(effects
				(font
					(size 1.27 1.27)
				)
				(justify left bottom)
				(hide yes)
			)
		)
		(property "Value" "GND"
			(at 295.91 190.5 0)
			(effects
				(font
					(size 1.27 1.27)
					(thickness 0.15)
				)
			)
		)
		(property "Footprint" ""
			(at 304.8 194.31 0)
			(effects
				(font
					(size 1.27 1.27)
					(thickness 0.15)
				)
				(justify left bottom)
				(hide yes)
			)
		)
		(property "Datasheet" ""
			(at 304.8 199.39 0)
			(effects
				(font
					(size 1.27 1.27)
					(thickness 0.15)
				)
				(justify left bottom)
				(hide yes)
			)
		)
		(property "Description" ""
			(at 295.91 186.69 0)
			(effects
				(font
					(size 1.27 1.27)
				)
				(hide yes)
			)
		)
		(property "Author" "Antmicro"
			(at 304.8 194.31 0)
			(effects
				(font
					(size 1.27 1.27)
					(thickness 0.15)
				)
				(justify left bottom)
				(hide yes)
			)
		)
		(property "License" "Apache-2.0"
			(at 304.8 196.85 0)
			(effects
				(font
					(size 1.27 1.27)
					(thickness 0.15)
				)
				(justify left bottom)
				(hide yes)
			)
		)
		(pin "1"
		)
		(instances
			(project "jetson-orin-baseboard"
				(path ""
					(reference "#PWR0244")
					(unit 1)
				)
			)
		)
	)
	(symbol
		(lib_id "antmicroCapacitors0402:C_100n_0402")
		(at 29.21 156.21 270)
		(mirror x)
		(unit 1)
		(exclude_from_sim no)
		(in_bom yes)
		(on_board yes)
		(dnp no)
		(property "Reference" "C44"
			(at 27.305 152.4 90)
			(effects
				(font
					(size 1.27 1.27)
				)
				(justify right)
			)
		)
		(property "Value" "C_100n_0402"
			(at 19.05 135.89 0)
			(effects
				(font
					(size 1.27 1.27)
					(thickness 0.15)
				)
				(justify left bottom)
				(hide yes)
			)
		)
		(property "Footprint" "antmicro-footprints:C_0402_1005Metric"
			(at 16.51 135.89 0)
			(effects
				(font
					(size 1.27 1.27)
					(thickness 0.15)
				)
				(justify left bottom)
				(hide yes)
			)
		)
		(property "Datasheet" "https://www.murata.com/products/productdetail?partno=GRM155R61H104KE14%23"
			(at 13.97 135.89 0)
			(effects
				(font
					(size 1.27 1.27)
					(thickness 0.15)
				)
				(justify left bottom)
				(hide yes)
			)
		)
		(property "Description" ""
			(at 29.21 156.21 0)
			(effects
				(font
					(size 1.27 1.27)
				)
				(hide yes)
			)
		)
		(property "Manufacturer" "Murata"
			(at 8.89 135.89 0)
			(effects
				(font
					(size 1.27 1.27)
					(thickness 0.15)
				)
				(justify left bottom)
				(hide yes)
			)
		)
		(property "MPN" "GRM155R61H104KE14D"
			(at 11.43 135.89 0)
			(effects
				(font
					(size 1.27 1.27)
					(thickness 0.15)
				)
				(justify left bottom)
				(hide yes)
			)
		)
		(property "Val" "100n"
			(at 27.305 154.94 90)
			(effects
				(font
					(size 1.27 1.27)
					(thickness 0.15)
				)
				(justify right)
			)
		)
		(property "License" "Apache-2.0"
			(at 6.35 135.89 0)
			(effects
				(font
					(size 1.27 1.27)
					(thickness 0.15)
				)
				(justify left bottom)
				(hide yes)
			)
		)
		(property "Author" "Antmicro"
			(at 3.81 135.89 0)
			(effects
				(font
					(size 1.27 1.27)
					(thickness 0.15)
				)
				(justify left bottom)
				(hide yes)
			)
		)
		(property "Voltage" "50V"
			(at 1.27 135.89 0)
			(effects
				(font
					(size 1.27 1.27)
				)
				(justify left bottom)
				(hide yes)
			)
		)
		(property "Dielectric" "X5R"
			(at -1.27 135.89 0)
			(effects
				(font
					(size 1.27 1.27)
				)
				(justify left bottom)
				(hide yes)
			)
		)
		(pin "1"
		)
		(pin "2"
		)
		(instances
			(project "jetson-orin-baseboard"
				(path ""
					(reference "C44")
					(unit 1)
				)
			)
		)
	)
	(symbol
		(lib_id "antmicropower:GND")
		(at 29.21 158.75 0)
		(unit 1)
		(exclude_from_sim no)
		(in_bom yes)
		(on_board yes)
		(dnp no)
		(fields_autoplaced yes)
		(property "Reference" "#PWR0218"
			(at 29.21 165.1 0)
			(effects
				(font
					(size 1.27 1.27)
				)
				(justify left bottom)
				(hide yes)
			)
		)
		(property "Value" "GND"
			(at 29.21 162.56 0)
			(effects
				(font
					(size 1.27 1.27)
					(thickness 0.15)
				)
			)
		)
		(property "Footprint" ""
			(at 38.1 166.37 0)
			(effects
				(font
					(size 1.27 1.27)
					(thickness 0.15)
				)
				(justify left bottom)
				(hide yes)
			)
		)
		(property "Datasheet" ""
			(at 38.1 171.45 0)
			(effects
				(font
					(size 1.27 1.27)
					(thickness 0.15)
				)
				(justify left bottom)
				(hide yes)
			)
		)
		(property "Description" ""
			(at 29.21 158.75 0)
			(effects
				(font
					(size 1.27 1.27)
				)
				(hide yes)
			)
		)
		(property "Author" "Antmicro"
			(at 38.1 166.37 0)
			(effects
				(font
					(size 1.27 1.27)
					(thickness 0.15)
				)
				(justify left bottom)
				(hide yes)
			)
		)
		(property "License" "Apache-2.0"
			(at 38.1 168.91 0)
			(effects
				(font
					(size 1.27 1.27)
					(thickness 0.15)
				)
				(justify left bottom)
				(hide yes)
			)
		)
		(pin "1"
		)
		(instances
			(project "jetson-orin-baseboard"
				(path ""
					(reference "#PWR0218")
					(unit 1)
				)
			)
		)
	)
	(symbol
		(lib_id "antmicroResistors0603:R_0R_22.4A_0603")
		(at 279.4 168.91 270)
		(unit 1)
		(exclude_from_sim no)
		(in_bom yes)
		(on_board yes)
		(dnp no)
		(property "Reference" "R233"
			(at 280.67 170.18 90)
			(effects
				(font
					(size 1.27 1.27)
				)
				(justify left)
			)
		)
		(property "Value" "R_0R_22.4A_0603"
			(at 281.94 170.18 90)
			(effects
				(font
					(size 1.27 1.27)
					(thickness 0.15)
				)
				(justify left)
				(hide yes)
			)
		)
		(property "Footprint" "antmicro-footprints:R_0603_1608Metric"
			(at 269.24 184.15 0)
			(effects
				(font
					(size 1.27 1.27)
					(thickness 0.15)
				)
				(justify left bottom)
				(hide yes)
			)
		)
		(property "Datasheet" "https://fscdn.rohm.com/en/products/databook/datasheet/passive/resistor/chip_resistor/pmr-jpw-e.pdf"
			(at 266.7 184.15 0)
			(effects
				(font
					(size 1.27 1.27)
					(thickness 0.15)
				)
				(justify left bottom)
				(hide yes)
			)
		)
		(property "Description" ""
			(at 279.4 168.91 0)
			(effects
				(font
					(size 1.27 1.27)
				)
				(hide yes)
			)
		)
		(property "Manufacturer" "ROHM Semiconductor"
			(at 261.62 184.15 0)
			(effects
				(font
					(size 1.27 1.27)
					(thickness 0.15)
				)
				(justify left bottom)
				(hide yes)
			)
		)
		(property "MPN" "PMR03EZPJ000"
			(at 264.16 184.15 0)
			(effects
				(font
					(size 1.27 1.27)
					(thickness 0.15)
				)
				(justify left bottom)
				(hide yes)
			)
		)
		(property "Val" "0R"
			(at 280.67 172.72 90)
			(effects
				(font
					(size 1.27 1.27)
					(thickness 0.15)
				)
				(justify left)
			)
		)
		(property "Author" "Antmicro"
			(at 256.54 184.15 0)
			(effects
				(font
					(size 1.27 1.27)
					(thickness 0.15)
				)
				(justify left bottom)
				(hide yes)
			)
		)
		(property "License" "Apache-2.0"
			(at 254 184.15 0)
			(effects
				(font
					(size 1.27 1.27)
					(thickness 0.15)
				)
				(justify left bottom)
				(hide yes)
			)
		)
		(property "Max. Curr." "22.4A"
			(at 277.495 168.275 0)
			(effects
				(font
					(size 1.27 1.27)
					(thickness 0.15)
				)
				(justify left)
			)
		)
		(property "Tolerance" "template_tolerance"
			(at 269.24 189.23 0)
			(effects
				(font
					(size 1.27 1.27)
				)
				(justify left bottom)
				(hide yes)
			)
		)
		(pin "1"
		)
		(pin "2"
		)
		(instances
			(project "jetson-orin-baseboard"
				(path ""
					(reference "R233")
					(unit 1)
				)
			)
		)
	)
	(symbol
		(lib_id "antmicropower:+1V8")
		(at 261.62 224.79 0)
		(unit 1)
		(exclude_from_sim no)
		(in_bom yes)
		(on_board yes)
		(dnp no)
		(property "Reference" "#PWR0234"
			(at 261.62 228.6 0)
			(effects
				(font
					(size 1.27 1.27)
				)
				(justify left bottom)
				(hide yes)
			)
		)
		(property "Value" "+1V8"
			(at 258.445 220.98 0)
			(effects
				(font
					(size 1.27 1.27)
					(thickness 0.15)
				)
				(justify left)
			)
		)
		(property "Footprint" ""
			(at 276.86 232.41 0)
			(effects
				(font
					(size 1.27 1.27)
					(thickness 0.15)
				)
				(justify left bottom)
				(hide yes)
			)
		)
		(property "Datasheet" ""
			(at 276.86 234.95 0)
			(effects
				(font
					(size 1.27 1.27)
					(thickness 0.15)
				)
				(justify left bottom)
				(hide yes)
			)
		)
		(property "Description" ""
			(at 261.62 224.79 0)
			(effects
				(font
					(size 1.27 1.27)
				)
				(hide yes)
			)
		)
		(property "Author" "Antmicro"
			(at 276.86 229.87 0)
			(effects
				(font
					(size 1.27 1.27)
					(thickness 0.15)
				)
				(justify left bottom)
				(hide yes)
			)
		)
		(property "License" "Apache-2.0"
			(at 276.86 232.41 0)
			(effects
				(font
					(size 1.27 1.27)
					(thickness 0.15)
				)
				(justify left bottom)
				(hide yes)
			)
		)
		(pin "1"
		)
		(instances
			(project "jetson-orin-baseboard"
				(path ""
					(reference "#PWR0234")
					(unit 1)
				)
			)
		)
	)
	(symbol
		(lib_id "antmicroCapacitors0402:C_1u_0402")
		(at 279.4 185.42 90)
		(unit 1)
		(exclude_from_sim no)
		(in_bom yes)
		(on_board yes)
		(dnp no)
		(property "Reference" "C105"
			(at 281.305 181.61 90)
			(effects
				(font
					(size 1.27 1.27)
				)
				(justify right)
			)
		)
		(property "Value" "C_1u_0402"
			(at 289.56 165.1 0)
			(effects
				(font
					(size 1.27 1.27)
					(thickness 0.15)
				)
				(justify left bottom)
				(hide yes)
			)
		)
		(property "Footprint" "antmicro-footprints:C_0402_1005Metric"
			(at 292.1 165.1 0)
			(effects
				(font
					(size 1.27 1.27)
					(thickness 0.15)
				)
				(justify left bottom)
				(hide yes)
			)
		)
		(property "Datasheet" "https://product.tdk.com/en/search/capacitor/ceramic/mlcc/info?part_no=C1005X6S1A105K050BC"
			(at 294.64 165.1 0)
			(effects
				(font
					(size 1.27 1.27)
					(thickness 0.15)
				)
				(justify left bottom)
				(hide yes)
			)
		)
		(property "Description" ""
			(at 279.4 185.42 0)
			(effects
				(font
					(size 1.27 1.27)
				)
				(hide yes)
			)
		)
		(property "Manufacturer" "TDK"
			(at 299.72 165.1 0)
			(effects
				(font
					(size 1.27 1.27)
					(thickness 0.15)
				)
				(justify left bottom)
				(hide yes)
			)
		)
		(property "MPN" "C1005X6S1A105K050BC"
			(at 297.18 165.1 0)
			(effects
				(font
					(size 1.27 1.27)
					(thickness 0.15)
				)
				(justify left bottom)
				(hide yes)
			)
		)
		(property "Val" "1u"
			(at 281.305 184.15 90)
			(effects
				(font
					(size 1.27 1.27)
					(thickness 0.15)
				)
				(justify right)
			)
		)
		(property "License" "Apache-2.0"
			(at 302.26 165.1 0)
			(effects
				(font
					(size 1.27 1.27)
					(thickness 0.15)
				)
				(justify left bottom)
				(hide yes)
			)
		)
		(property "Author" "Antmicro"
			(at 304.8 165.1 0)
			(effects
				(font
					(size 1.27 1.27)
					(thickness 0.15)
				)
				(justify left bottom)
				(hide yes)
			)
		)
		(property "Voltage" ""
			(at 307.34 165.1 0)
			(effects
				(font
					(size 1.27 1.27)
				)
				(justify left bottom)
				(hide yes)
			)
		)
		(property "Dielectric" ""
			(at 309.88 165.1 0)
			(effects
				(font
					(size 1.27 1.27)
				)
				(justify left bottom)
				(hide yes)
			)
		)
		(pin "1"
		)
		(pin "2"
		)
		(instances
			(project "jetson-orin-baseboard"
				(path ""
					(reference "C105")
					(unit 1)
				)
			)
		)
	)
	(symbol
		(lib_id "antmicroTransistorsFETsMOSFETsSingle:PJE138K")
		(at 143.51 254 0)
		(unit 1)
		(exclude_from_sim no)
		(in_bom yes)
		(on_board yes)
		(dnp no)
		(property "Reference" "Q9"
			(at 152.4 250.19 0)
			(effects
				(font
					(size 1.27 1.27)
					(thickness 0.15)
				)
				(justify left)
			)
		)
		(property "Value" "PJE138K"
			(at 166.37 262.89 0)
			(effects
				(font
					(size 1.27 1.27)
					(thickness 0.15)
				)
				(justify left bottom)
				(hide yes)
			)
		)
		(property "Footprint" "antmicro-footprints:SOT-523"
			(at 166.37 265.43 0)
			(effects
				(font
					(size 1.27 1.27)
					(thickness 0.15)
				)
				(justify left bottom)
				(hide yes)
			)
		)
		(property "Datasheet" "https://www.mouser.com/datasheet/2/1057/PJE138K-1876698.pdf"
			(at 166.37 267.97 0)
			(effects
				(font
					(size 1.27 1.27)
					(thickness 0.15)
				)
				(justify left bottom)
				(hide yes)
			)
		)
		(property "Description" ""
			(at 143.51 254 0)
			(effects
				(font
					(size 1.27 1.27)
				)
				(hide yes)
			)
		)
		(property "MPN" "PJE138K_R1_00001"
			(at 152.4 252.73 0)
			(effects
				(font
					(size 1.27 1.27)
					(thickness 0.15)
				)
				(justify left)
			)
		)
		(property "Manufacturer" "PANJIT"
			(at 166.37 273.05 0)
			(effects
				(font
					(size 1.27 1.27)
					(thickness 0.15)
				)
				(justify left bottom)
				(hide yes)
			)
		)
		(property "Author" "Antmicro"
			(at 166.37 275.59 0)
			(effects
				(font
					(size 1.27 1.27)
					(thickness 0.15)
				)
				(justify left bottom)
				(hide yes)
			)
		)
		(property "License" "Apache-2.0"
			(at 166.37 278.13 0)
			(effects
				(font
					(size 1.27 1.27)
					(thickness 0.15)
				)
				(justify left bottom)
				(hide yes)
			)
		)
		(pin "2"
		)
		(pin "3"
		)
		(pin "1"
		)
		(instances
			(project "jetson-orin-baseboard"
				(path ""
					(reference "Q9")
					(unit 1)
				)
			)
		)
	)
	(symbol
		(lib_id "antmicropower:GND")
		(at 76.2 247.65 0)
		(unit 1)
		(exclude_from_sim no)
		(in_bom yes)
		(on_board yes)
		(dnp no)
		(fields_autoplaced yes)
		(property "Reference" "#PWR0351"
			(at 76.2 254 0)
			(effects
				(font
					(size 1.27 1.27)
				)
				(justify left bottom)
				(hide yes)
			)
		)
		(property "Value" "GND"
			(at 76.2 251.46 0)
			(effects
				(font
					(size 1.27 1.27)
					(thickness 0.15)
				)
			)
		)
		(property "Footprint" ""
			(at 85.09 255.27 0)
			(effects
				(font
					(size 1.27 1.27)
					(thickness 0.15)
				)
				(justify left bottom)
				(hide yes)
			)
		)
		(property "Datasheet" ""
			(at 85.09 260.35 0)
			(effects
				(font
					(size 1.27 1.27)
					(thickness 0.15)
				)
				(justify left bottom)
				(hide yes)
			)
		)
		(property "Description" ""
			(at 76.2 247.65 0)
			(effects
				(font
					(size 1.27 1.27)
				)
				(hide yes)
			)
		)
		(property "Author" "Antmicro"
			(at 85.09 255.27 0)
			(effects
				(font
					(size 1.27 1.27)
					(thickness 0.15)
				)
				(justify left bottom)
				(hide yes)
			)
		)
		(property "License" "Apache-2.0"
			(at 85.09 257.81 0)
			(effects
				(font
					(size 1.27 1.27)
					(thickness 0.15)
				)
				(justify left bottom)
				(hide yes)
			)
		)
		(pin "1"
		)
		(instances
			(project "jetson-orin-baseboard"
				(path ""
					(reference "#PWR0351")
					(unit 1)
				)
			)
		)
	)
	(symbol
		(lib_id "antmicroTVSDiodes:TPD1E0B04_XDFN-2")
		(at 388.62 157.48 0)
		(unit 1)
		(exclude_from_sim no)
		(in_bom yes)
		(on_board yes)
		(dnp no)
		(property "Reference" "D22"
			(at 393.065 156.845 0)
			(effects
				(font
					(size 1.27 1.27)
				)
				(justify left bottom)
			)
		)
		(property "Value" "TPD1E0B04_XDFN-2"
			(at 403.86 167.64 0)
			(effects
				(font
					(size 1.27 1.27)
					(thickness 0.15)
				)
				(justify left bottom)
				(hide yes)
			)
		)
		(property "Footprint" "antmicro-footprints:XDFN-2_1x0.60mm"
			(at 403.86 162.56 0)
			(effects
				(font
					(size 1.27 1.27)
					(thickness 0.15)
				)
				(justify left bottom)
				(hide yes)
			)
		)
		(property "Datasheet" "https://www.ti.com/general/docs/suppproductinfo.tsp?distId=26&gotoUrl=https://www.ti.com/lit/gpn/tpd1e0b04"
			(at 403.86 165.1 0)
			(effects
				(font
					(size 1.27 1.27)
					(thickness 0.15)
				)
				(justify left bottom)
				(hide yes)
			)
		)
		(property "Description" ""
			(at 388.62 157.48 0)
			(effects
				(font
					(size 1.27 1.27)
				)
				(hide yes)
			)
		)
		(property "Manufacturer" "Texas Instruments"
			(at 403.86 170.18 0)
			(effects
				(font
					(size 1.27 1.27)
					(thickness 0.15)
				)
				(justify left bottom)
				(hide yes)
			)
		)
		(property "MPN" "TPD1E0B04DPYR"
			(at 373.38 156.845 0)
			(effects
				(font
					(size 1.27 1.27)
					(thickness 0.15)
				)
				(justify left bottom)
			)
		)
		(property "Author" "Antmicro"
			(at 403.86 172.72 0)
			(effects
				(font
					(size 1.27 1.27)
					(thickness 0.15)
				)
				(justify left bottom)
				(hide yes)
			)
		)
		(property "License" "Apache-2.0"
			(at 403.86 175.26 0)
			(effects
				(font
					(size 1.27 1.27)
					(thickness 0.15)
				)
				(justify left bottom)
				(hide yes)
			)
		)
		(pin "1"
		)
		(pin "2"
		)
		(instances
			(project "jetson-orin-baseboard"
				(path ""
					(reference "D22")
					(unit 1)
				)
			)
		)
	)
	(symbol
		(lib_id "antmicropower:GND")
		(at 194.31 55.88 0)
		(unit 1)
		(exclude_from_sim no)
		(in_bom yes)
		(on_board yes)
		(dnp no)
		(fields_autoplaced yes)
		(property "Reference" "#PWR0213"
			(at 194.31 62.23 0)
			(effects
				(font
					(size 1.27 1.27)
				)
				(justify left bottom)
				(hide yes)
			)
		)
		(property "Value" "GND"
			(at 194.31 59.69 0)
			(effects
				(font
					(size 1.27 1.27)
					(thickness 0.15)
				)
			)
		)
		(property "Footprint" ""
			(at 203.2 63.5 0)
			(effects
				(font
					(size 1.27 1.27)
					(thickness 0.15)
				)
				(justify left bottom)
				(hide yes)
			)
		)
		(property "Datasheet" ""
			(at 203.2 68.58 0)
			(effects
				(font
					(size 1.27 1.27)
					(thickness 0.15)
				)
				(justify left bottom)
				(hide yes)
			)
		)
		(property "Description" ""
			(at 194.31 55.88 0)
			(effects
				(font
					(size 1.27 1.27)
				)
				(hide yes)
			)
		)
		(property "Author" "Antmicro"
			(at 203.2 63.5 0)
			(effects
				(font
					(size 1.27 1.27)
					(thickness 0.15)
				)
				(justify left bottom)
				(hide yes)
			)
		)
		(property "License" "Apache-2.0"
			(at 203.2 66.04 0)
			(effects
				(font
					(size 1.27 1.27)
					(thickness 0.15)
				)
				(justify left bottom)
				(hide yes)
			)
		)
		(pin "1"
		)
		(instances
			(project "jetson-orin-baseboard"
				(path ""
					(reference "#PWR0213")
					(unit 1)
				)
			)
		)
	)
	(symbol
		(lib_id "antmicropower:GND")
		(at 162.56 58.42 0)
		(unit 1)
		(exclude_from_sim no)
		(in_bom yes)
		(on_board yes)
		(dnp no)
		(fields_autoplaced yes)
		(property "Reference" "#PWR0185"
			(at 162.56 64.77 0)
			(effects
				(font
					(size 1.27 1.27)
				)
				(justify left bottom)
				(hide yes)
			)
		)
		(property "Value" "GND"
			(at 162.56 62.23 0)
			(effects
				(font
					(size 1.27 1.27)
					(thickness 0.15)
				)
			)
		)
		(property "Footprint" ""
			(at 171.45 66.04 0)
			(effects
				(font
					(size 1.27 1.27)
					(thickness 0.15)
				)
				(justify left bottom)
				(hide yes)
			)
		)
		(property "Datasheet" ""
			(at 171.45 71.12 0)
			(effects
				(font
					(size 1.27 1.27)
					(thickness 0.15)
				)
				(justify left bottom)
				(hide yes)
			)
		)
		(property "Description" ""
			(at 162.56 58.42 0)
			(effects
				(font
					(size 1.27 1.27)
				)
				(hide yes)
			)
		)
		(property "Author" "Antmicro"
			(at 171.45 66.04 0)
			(effects
				(font
					(size 1.27 1.27)
					(thickness 0.15)
				)
				(justify left bottom)
				(hide yes)
			)
		)
		(property "License" "Apache-2.0"
			(at 171.45 68.58 0)
			(effects
				(font
					(size 1.27 1.27)
					(thickness 0.15)
				)
				(justify left bottom)
				(hide yes)
			)
		)
		(pin "1"
		)
		(instances
			(project "jetson-orin-baseboard"
				(path ""
					(reference "#PWR0185")
					(unit 1)
				)
			)
		)
	)
	(symbol
		(lib_id "antmicroTVSDiodes:TPD1E0B04_XDFN-2")
		(at 388.62 243.84 0)
		(unit 1)
		(exclude_from_sim no)
		(in_bom yes)
		(on_board yes)
		(dnp no)
		(property "Reference" "D21"
			(at 393.065 243.205 0)
			(effects
				(font
					(size 1.27 1.27)
				)
				(justify left bottom)
			)
		)
		(property "Value" "TPD1E0B04_XDFN-2"
			(at 403.86 254 0)
			(effects
				(font
					(size 1.27 1.27)
					(thickness 0.15)
				)
				(justify left bottom)
				(hide yes)
			)
		)
		(property "Footprint" "antmicro-footprints:XDFN-2_1x0.60mm"
			(at 403.86 248.92 0)
			(effects
				(font
					(size 1.27 1.27)
					(thickness 0.15)
				)
				(justify left bottom)
				(hide yes)
			)
		)
		(property "Datasheet" "https://www.ti.com/general/docs/suppproductinfo.tsp?distId=26&gotoUrl=https://www.ti.com/lit/gpn/tpd1e0b04"
			(at 403.86 251.46 0)
			(effects
				(font
					(size 1.27 1.27)
					(thickness 0.15)
				)
				(justify left bottom)
				(hide yes)
			)
		)
		(property "Description" ""
			(at 388.62 243.84 0)
			(effects
				(font
					(size 1.27 1.27)
				)
				(hide yes)
			)
		)
		(property "Manufacturer" "Texas Instruments"
			(at 403.86 256.54 0)
			(effects
				(font
					(size 1.27 1.27)
					(thickness 0.15)
				)
				(justify left bottom)
				(hide yes)
			)
		)
		(property "MPN" "TPD1E0B04DPYR"
			(at 373.38 243.205 0)
			(effects
				(font
					(size 1.27 1.27)
					(thickness 0.15)
				)
				(justify left bottom)
			)
		)
		(property "Author" "Antmicro"
			(at 403.86 259.08 0)
			(effects
				(font
					(size 1.27 1.27)
					(thickness 0.15)
				)
				(justify left bottom)
				(hide yes)
			)
		)
		(property "License" "Apache-2.0"
			(at 403.86 261.62 0)
			(effects
				(font
					(size 1.27 1.27)
					(thickness 0.15)
				)
				(justify left bottom)
				(hide yes)
			)
		)
		(pin "1"
		)
		(pin "2"
		)
		(instances
			(project "jetson-orin-baseboard"
				(path ""
					(reference "D21")
					(unit 1)
				)
			)
		)
	)
	(symbol
		(lib_id "antmicropower:GND")
		(at 73.66 175.26 0)
		(unit 1)
		(exclude_from_sim no)
		(in_bom yes)
		(on_board yes)
		(dnp no)
		(fields_autoplaced yes)
		(property "Reference" "#PWR0227"
			(at 73.66 181.61 0)
			(effects
				(font
					(size 1.27 1.27)
				)
				(justify left bottom)
				(hide yes)
			)
		)
		(property "Value" "GND"
			(at 73.66 179.07 0)
			(effects
				(font
					(size 1.27 1.27)
					(thickness 0.15)
				)
			)
		)
		(property "Footprint" ""
			(at 82.55 182.88 0)
			(effects
				(font
					(size 1.27 1.27)
					(thickness 0.15)
				)
				(justify left bottom)
				(hide yes)
			)
		)
		(property "Datasheet" ""
			(at 82.55 187.96 0)
			(effects
				(font
					(size 1.27 1.27)
					(thickness 0.15)
				)
				(justify left bottom)
				(hide yes)
			)
		)
		(property "Description" ""
			(at 73.66 175.26 0)
			(effects
				(font
					(size 1.27 1.27)
				)
				(hide yes)
			)
		)
		(property "Author" "Antmicro"
			(at 82.55 182.88 0)
			(effects
				(font
					(size 1.27 1.27)
					(thickness 0.15)
				)
				(justify left bottom)
				(hide yes)
			)
		)
		(property "License" "Apache-2.0"
			(at 82.55 185.42 0)
			(effects
				(font
					(size 1.27 1.27)
					(thickness 0.15)
				)
				(justify left bottom)
				(hide yes)
			)
		)
		(pin "1"
		)
		(instances
			(project "jetson-orin-baseboard"
				(path ""
					(reference "#PWR0227")
					(unit 1)
				)
			)
		)
	)
	(symbol
		(lib_id "antmicroResistors0402:R_0R_0402")
		(at 41.91 71.12 0)
		(unit 1)
		(exclude_from_sim no)
		(in_bom yes)
		(on_board yes)
		(dnp no)
		(property "Reference" "R215"
			(at 46.99 70.485 0)
			(effects
				(font
					(size 1.27 1.27)
				)
				(justify left bottom)
			)
		)
		(property "Value" "R_0R_0402"
			(at 62.23 83.82 0)
			(effects
				(font
					(size 1.27 1.27)
					(thickness 0.15)
				)
				(justify left bottom)
				(hide yes)
			)
		)
		(property "Footprint" "antmicro-footprints:R_0402_1005Metric"
			(at 62.23 86.36 0)
			(effects
				(font
					(size 1.27 1.27)
					(thickness 0.15)
				)
				(justify left bottom)
				(hide yes)
			)
		)
		(property "Datasheet" "https://industrial.panasonic.com/cdbs/www-data/pdf/RDA0000/AOA0000C301.pdf"
			(at 62.23 88.9 0)
			(effects
				(font
					(size 1.27 1.27)
					(thickness 0.15)
				)
				(justify left bottom)
				(hide yes)
			)
		)
		(property "Description" ""
			(at 41.91 71.12 0)
			(effects
				(font
					(size 1.27 1.27)
				)
				(hide yes)
			)
		)
		(property "Manufacturer" "Panasonic"
			(at 62.23 93.98 0)
			(effects
				(font
					(size 1.27 1.27)
					(thickness 0.15)
				)
				(justify left bottom)
				(hide yes)
			)
		)
		(property "MPN" "ERJ2GE0R00X"
			(at 62.23 91.44 0)
			(effects
				(font
					(size 1.27 1.27)
					(thickness 0.15)
				)
				(justify left bottom)
				(hide yes)
			)
		)
		(property "Val" "0R"
			(at 39.37 70.485 0)
			(effects
				(font
					(size 1.27 1.27)
					(thickness 0.15)
				)
				(justify left bottom)
			)
		)
		(property "License" "Apache-2.0"
			(at 62.23 96.52 0)
			(effects
				(font
					(size 1.27 1.27)
					(thickness 0.15)
				)
				(justify left bottom)
				(hide yes)
			)
		)
		(property "Author" "Antmicro"
			(at 62.23 99.06 0)
			(effects
				(font
					(size 1.27 1.27)
					(thickness 0.15)
				)
				(justify left bottom)
				(hide yes)
			)
		)
		(property "Tolerance" "~"
			(at 62.23 81.28 0)
			(effects
				(font
					(size 1.27 1.27)
				)
				(justify left bottom)
				(hide yes)
			)
		)
		(property "Current" "1A"
			(at 62.23 101.6 0)
			(effects
				(font
					(size 1.27 1.27)
					(thickness 0.15)
				)
				(justify left bottom)
				(hide yes)
			)
		)
		(pin "1"
		)
		(pin "2"
		)
		(instances
			(project "jetson-orin-baseboard"
				(path ""
					(reference "R215")
					(unit 1)
				)
			)
		)
	)
	(symbol
		(lib_id "antmicropower:GND")
		(at 55.88 88.9 0)
		(unit 1)
		(exclude_from_sim no)
		(in_bom yes)
		(on_board yes)
		(dnp no)
		(fields_autoplaced yes)
		(property "Reference" "#PWR0204"
			(at 55.88 95.25 0)
			(effects
				(font
					(size 1.27 1.27)
				)
				(justify left bottom)
				(hide yes)
			)
		)
		(property "Value" "GND"
			(at 55.88 92.71 0)
			(effects
				(font
					(size 1.27 1.27)
					(thickness 0.15)
				)
			)
		)
		(property "Footprint" ""
			(at 64.77 96.52 0)
			(effects
				(font
					(size 1.27 1.27)
					(thickness 0.15)
				)
				(justify left bottom)
				(hide yes)
			)
		)
		(property "Datasheet" ""
			(at 64.77 101.6 0)
			(effects
				(font
					(size 1.27 1.27)
					(thickness 0.15)
				)
				(justify left bottom)
				(hide yes)
			)
		)
		(property "Description" ""
			(at 55.88 88.9 0)
			(effects
				(font
					(size 1.27 1.27)
				)
				(hide yes)
			)
		)
		(property "Author" "Antmicro"
			(at 64.77 96.52 0)
			(effects
				(font
					(size 1.27 1.27)
					(thickness 0.15)
				)
				(justify left bottom)
				(hide yes)
			)
		)
		(property "License" "Apache-2.0"
			(at 64.77 99.06 0)
			(effects
				(font
					(size 1.27 1.27)
					(thickness 0.15)
				)
				(justify left bottom)
				(hide yes)
			)
		)
		(pin "1"
		)
		(instances
			(project "jetson-orin-baseboard"
				(path ""
					(reference "#PWR0204")
					(unit 1)
				)
			)
		)
	)
	(symbol
		(lib_id "antmicroResistors0402:R_0R_0402")
		(at 55.88 87.63 90)
		(unit 1)
		(exclude_from_sim no)
		(in_bom yes)
		(on_board yes)
		(dnp no)
		(property "Reference" "R218"
			(at 57.15 83.82 90)
			(effects
				(font
					(size 1.27 1.27)
				)
				(justify right)
			)
		)
		(property "Value" "R_0R_0402"
			(at 68.58 67.31 0)
			(effects
				(font
					(size 1.27 1.27)
					(thickness 0.15)
				)
				(justify left bottom)
				(hide yes)
			)
		)
		(property "Footprint" "antmicro-footprints:R_0402_1005Metric"
			(at 71.12 67.31 0)
			(effects
				(font
					(size 1.27 1.27)
					(thickness 0.15)
				)
				(justify left bottom)
				(hide yes)
			)
		)
		(property "Datasheet" "https://industrial.panasonic.com/cdbs/www-data/pdf/RDA0000/AOA0000C301.pdf"
			(at 73.66 67.31 0)
			(effects
				(font
					(size 1.27 1.27)
					(thickness 0.15)
				)
				(justify left bottom)
				(hide yes)
			)
		)
		(property "Description" ""
			(at 55.88 87.63 0)
			(effects
				(font
					(size 1.27 1.27)
				)
				(hide yes)
			)
		)
		(property "Manufacturer" "Panasonic"
			(at 78.74 67.31 0)
			(effects
				(font
					(size 1.27 1.27)
					(thickness 0.15)
				)
				(justify left bottom)
				(hide yes)
			)
		)
		(property "MPN" "ERJ2GE0R00X"
			(at 76.2 67.31 0)
			(effects
				(font
					(size 1.27 1.27)
					(thickness 0.15)
				)
				(justify left bottom)
				(hide yes)
			)
		)
		(property "Val" "0R"
			(at 57.15 86.36 90)
			(effects
				(font
					(size 1.27 1.27)
					(thickness 0.15)
				)
				(justify right)
			)
		)
		(property "License" "Apache-2.0"
			(at 81.28 67.31 0)
			(effects
				(font
					(size 1.27 1.27)
					(thickness 0.15)
				)
				(justify left bottom)
				(hide yes)
			)
		)
		(property "Author" "Antmicro"
			(at 83.82 67.31 0)
			(effects
				(font
					(size 1.27 1.27)
					(thickness 0.15)
				)
				(justify left bottom)
				(hide yes)
			)
		)
		(property "Tolerance" "~"
			(at 66.04 67.31 0)
			(effects
				(font
					(size 1.27 1.27)
				)
				(justify left bottom)
				(hide yes)
			)
		)
		(property "Current" "1A"
			(at 86.36 67.31 0)
			(effects
				(font
					(size 1.27 1.27)
					(thickness 0.15)
				)
				(justify left bottom)
				(hide yes)
			)
		)
		(pin "1"
		)
		(pin "2"
		)
		(instances
			(project "jetson-orin-baseboard"
				(path ""
					(reference "R218")
					(unit 1)
				)
			)
		)
	)
	(symbol
		(lib_id "antmicroResistors0402:R_200R_0402")
		(at 149.86 238.76 90)
		(unit 1)
		(exclude_from_sim no)
		(in_bom yes)
		(on_board yes)
		(dnp no)
		(property "Reference" "R223"
			(at 151.13 234.95 90)
			(effects
				(font
					(size 1.27 1.27)
				)
				(justify right)
			)
		)
		(property "Value" "R_200R_0402"
			(at 162.56 218.44 0)
			(effects
				(font
					(size 1.27 1.27)
					(thickness 0.15)
				)
				(justify left bottom)
				(hide yes)
			)
		)
		(property "Footprint" "antmicro-footprints:R_0402_1005Metric"
			(at 165.1 218.44 0)
			(effects
				(font
					(size 1.27 1.27)
					(thickness 0.15)
				)
				(justify left bottom)
				(hide yes)
			)
		)
		(property "Datasheet" "https://www.bourns.com/docs/product-datasheets/cr.pdf"
			(at 167.64 218.44 0)
			(effects
				(font
					(size 1.27 1.27)
					(thickness 0.15)
				)
				(justify left bottom)
				(hide yes)
			)
		)
		(property "Description" ""
			(at 149.86 238.76 0)
			(effects
				(font
					(size 1.27 1.27)
				)
				(hide yes)
			)
		)
		(property "Manufacturer" "Bourns"
			(at 172.72 218.44 0)
			(effects
				(font
					(size 1.27 1.27)
					(thickness 0.15)
				)
				(justify left bottom)
				(hide yes)
			)
		)
		(property "MPN" "CR0402-FX-2000GLF"
			(at 170.18 218.44 0)
			(effects
				(font
					(size 1.27 1.27)
					(thickness 0.15)
				)
				(justify left bottom)
				(hide yes)
			)
		)
		(property "Val" "200R"
			(at 151.13 237.49 90)
			(effects
				(font
					(size 1.27 1.27)
					(thickness 0.15)
				)
				(justify right)
			)
		)
		(property "License" "Apache-2.0"
			(at 175.26 218.44 0)
			(effects
				(font
					(size 1.27 1.27)
					(thickness 0.15)
				)
				(justify left bottom)
				(hide yes)
			)
		)
		(property "Author" "Antmicro"
			(at 177.8 218.44 0)
			(effects
				(font
					(size 1.27 1.27)
					(thickness 0.15)
				)
				(justify left bottom)
				(hide yes)
			)
		)
		(property "Tolerance" "1%"
			(at 160.02 218.44 0)
			(effects
				(font
					(size 1.27 1.27)
				)
				(justify left bottom)
				(hide yes)
			)
		)
		(pin "1"
		)
		(pin "2"
		)
		(instances
			(project "jetson-orin-baseboard"
				(path ""
					(reference "R223")
					(unit 1)
				)
			)
		)
	)
	(symbol
		(lib_id "antmicropower:GND")
		(at 208.28 261.62 0)
		(unit 1)
		(exclude_from_sim no)
		(in_bom yes)
		(on_board yes)
		(dnp no)
		(fields_autoplaced yes)
		(property "Reference" "#PWR0231"
			(at 208.28 267.97 0)
			(effects
				(font
					(size 1.27 1.27)
				)
				(justify left bottom)
				(hide yes)
			)
		)
		(property "Value" "GND"
			(at 208.28 265.43 0)
			(effects
				(font
					(size 1.27 1.27)
					(thickness 0.15)
				)
			)
		)
		(property "Footprint" ""
			(at 217.17 269.24 0)
			(effects
				(font
					(size 1.27 1.27)
					(thickness 0.15)
				)
				(justify left bottom)
				(hide yes)
			)
		)
		(property "Datasheet" ""
			(at 217.17 274.32 0)
			(effects
				(font
					(size 1.27 1.27)
					(thickness 0.15)
				)
				(justify left bottom)
				(hide yes)
			)
		)
		(property "Description" ""
			(at 208.28 261.62 0)
			(effects
				(font
					(size 1.27 1.27)
				)
				(hide yes)
			)
		)
		(property "Author" "Antmicro"
			(at 217.17 269.24 0)
			(effects
				(font
					(size 1.27 1.27)
					(thickness 0.15)
				)
				(justify left bottom)
				(hide yes)
			)
		)
		(property "License" "Apache-2.0"
			(at 217.17 271.78 0)
			(effects
				(font
					(size 1.27 1.27)
					(thickness 0.15)
				)
				(justify left bottom)
				(hide yes)
			)
		)
		(pin "1"
		)
		(instances
			(project "jetson-orin-baseboard"
				(path ""
					(reference "#PWR0231")
					(unit 1)
				)
			)
		)
	)
	(symbol
		(lib_id "antmicroTVSDiodes:TPD1E0B04_XDFN-2")
		(at 191.77 96.52 90)
		(unit 1)
		(exclude_from_sim no)
		(in_bom yes)
		(on_board yes)
		(dnp no)
		(fields_autoplaced yes)
		(property "Reference" "D57"
			(at 194.945 91.0034 90)
			(effects
				(font
					(size 1.27 1.27)
				)
				(justify right)
			)
		)
		(property "Value" "TPD1E0B04_XDFN-2"
			(at 201.93 81.28 0)
			(effects
				(font
					(size 1.27 1.27)
					(thickness 0.15)
				)
				(justify left bottom)
				(hide yes)
			)
		)
		(property "Footprint" "antmicro-footprints:XDFN-2_1x0.60mm"
			(at 196.85 81.28 0)
			(effects
				(font
					(size 1.27 1.27)
					(thickness 0.15)
				)
				(justify left bottom)
				(hide yes)
			)
		)
		(property "Datasheet" "https://www.ti.com/general/docs/suppproductinfo.tsp?distId=26&gotoUrl=https://www.ti.com/lit/gpn/tpd1e0b04"
			(at 199.39 81.28 0)
			(effects
				(font
					(size 1.27 1.27)
					(thickness 0.15)
				)
				(justify left bottom)
				(hide yes)
			)
		)
		(property "Description" ""
			(at 191.77 96.52 0)
			(effects
				(font
					(size 1.27 1.27)
				)
				(hide yes)
			)
		)
		(property "Manufacturer" "Texas Instruments"
			(at 204.47 81.28 0)
			(effects
				(font
					(size 1.27 1.27)
					(thickness 0.15)
				)
				(justify left bottom)
				(hide yes)
			)
		)
		(property "MPN" "TPD1E0B04DPYR"
			(at 194.945 93.5434 90)
			(effects
				(font
					(size 1.27 1.27)
					(thickness 0.15)
				)
				(justify right)
			)
		)
		(property "Author" "Antmicro"
			(at 207.01 81.28 0)
			(effects
				(font
					(size 1.27 1.27)
					(thickness 0.15)
				)
				(justify left bottom)
				(hide yes)
			)
		)
		(property "License" "Apache-2.0"
			(at 209.55 81.28 0)
			(effects
				(font
					(size 1.27 1.27)
					(thickness 0.15)
				)
				(justify left bottom)
				(hide yes)
			)
		)
		(pin "1"
		)
		(pin "2"
		)
		(instances
			(project "jetson-orin-baseboard"
				(path ""
					(reference "D57")
					(unit 1)
				)
			)
		)
	)
	(symbol
		(lib_id "antmicroTVSDiodes:TPD1E0B04_XDFN-2")
		(at 388.62 172.72 0)
		(unit 1)
		(exclude_from_sim no)
		(in_bom yes)
		(on_board yes)
		(dnp no)
		(property "Reference" "D40"
			(at 393.065 172.085 0)
			(effects
				(font
					(size 1.27 1.27)
				)
				(justify left bottom)
			)
		)
		(property "Value" "TPD1E0B04_XDFN-2"
			(at 403.86 182.88 0)
			(effects
				(font
					(size 1.27 1.27)
					(thickness 0.15)
				)
				(justify left bottom)
				(hide yes)
			)
		)
		(property "Footprint" "antmicro-footprints:XDFN-2_1x0.60mm"
			(at 403.86 177.8 0)
			(effects
				(font
					(size 1.27 1.27)
					(thickness 0.15)
				)
				(justify left bottom)
				(hide yes)
			)
		)
		(property "Datasheet" "https://www.ti.com/general/docs/suppproductinfo.tsp?distId=26&gotoUrl=https://www.ti.com/lit/gpn/tpd1e0b04"
			(at 403.86 180.34 0)
			(effects
				(font
					(size 1.27 1.27)
					(thickness 0.15)
				)
				(justify left bottom)
				(hide yes)
			)
		)
		(property "Description" ""
			(at 388.62 172.72 0)
			(effects
				(font
					(size 1.27 1.27)
				)
				(hide yes)
			)
		)
		(property "Manufacturer" "Texas Instruments"
			(at 403.86 185.42 0)
			(effects
				(font
					(size 1.27 1.27)
					(thickness 0.15)
				)
				(justify left bottom)
				(hide yes)
			)
		)
		(property "MPN" "TPD1E0B04DPYR"
			(at 373.38 172.085 0)
			(effects
				(font
					(size 1.27 1.27)
					(thickness 0.15)
				)
				(justify left bottom)
			)
		)
		(property "Author" "Antmicro"
			(at 403.86 187.96 0)
			(effects
				(font
					(size 1.27 1.27)
					(thickness 0.15)
				)
				(justify left bottom)
				(hide yes)
			)
		)
		(property "License" "Apache-2.0"
			(at 403.86 190.5 0)
			(effects
				(font
					(size 1.27 1.27)
					(thickness 0.15)
				)
				(justify left bottom)
				(hide yes)
			)
		)
		(pin "1"
		)
		(pin "2"
		)
		(instances
			(project "jetson-orin-baseboard"
				(path ""
					(reference "D40")
					(unit 1)
				)
			)
		)
	)
	(symbol
		(lib_id "antmicroResistors0402:R_0R_0402")
		(at 41.91 73.66 0)
		(unit 1)
		(exclude_from_sim no)
		(in_bom yes)
		(on_board yes)
		(dnp no)
		(property "Reference" "R216"
			(at 46.99 73.025 0)
			(effects
				(font
					(size 1.27 1.27)
				)
				(justify left bottom)
			)
		)
		(property "Value" "R_0R_0402"
			(at 62.23 86.36 0)
			(effects
				(font
					(size 1.27 1.27)
					(thickness 0.15)
				)
				(justify left bottom)
				(hide yes)
			)
		)
		(property "Footprint" "antmicro-footprints:R_0402_1005Metric"
			(at 62.23 88.9 0)
			(effects
				(font
					(size 1.27 1.27)
					(thickness 0.15)
				)
				(justify left bottom)
				(hide yes)
			)
		)
		(property "Datasheet" "https://industrial.panasonic.com/cdbs/www-data/pdf/RDA0000/AOA0000C301.pdf"
			(at 62.23 91.44 0)
			(effects
				(font
					(size 1.27 1.27)
					(thickness 0.15)
				)
				(justify left bottom)
				(hide yes)
			)
		)
		(property "Description" ""
			(at 41.91 73.66 0)
			(effects
				(font
					(size 1.27 1.27)
				)
				(hide yes)
			)
		)
		(property "Manufacturer" "Panasonic"
			(at 62.23 96.52 0)
			(effects
				(font
					(size 1.27 1.27)
					(thickness 0.15)
				)
				(justify left bottom)
				(hide yes)
			)
		)
		(property "MPN" "ERJ2GE0R00X"
			(at 62.23 93.98 0)
			(effects
				(font
					(size 1.27 1.27)
					(thickness 0.15)
				)
				(justify left bottom)
				(hide yes)
			)
		)
		(property "Val" "0R"
			(at 39.37 73.025 0)
			(effects
				(font
					(size 1.27 1.27)
					(thickness 0.15)
				)
				(justify left bottom)
			)
		)
		(property "License" "Apache-2.0"
			(at 62.23 99.06 0)
			(effects
				(font
					(size 1.27 1.27)
					(thickness 0.15)
				)
				(justify left bottom)
				(hide yes)
			)
		)
		(property "Author" "Antmicro"
			(at 62.23 101.6 0)
			(effects
				(font
					(size 1.27 1.27)
					(thickness 0.15)
				)
				(justify left bottom)
				(hide yes)
			)
		)
		(property "Tolerance" "~"
			(at 62.23 83.82 0)
			(effects
				(font
					(size 1.27 1.27)
				)
				(justify left bottom)
				(hide yes)
			)
		)
		(property "Current" "1A"
			(at 62.23 104.14 0)
			(effects
				(font
					(size 1.27 1.27)
					(thickness 0.15)
				)
				(justify left bottom)
				(hide yes)
			)
		)
		(pin "1"
		)
		(pin "2"
		)
		(instances
			(project "jetson-orin-baseboard"
				(path ""
					(reference "R216")
					(unit 1)
				)
			)
		)
	)
	(symbol
		(lib_id "antmicroTVSDiodes:TPD1E0B04_XDFN-2")
		(at 388.62 218.44 0)
		(unit 1)
		(exclude_from_sim no)
		(in_bom yes)
		(on_board yes)
		(dnp no)
		(property "Reference" "D49"
			(at 393.065 217.805 0)
			(effects
				(font
					(size 1.27 1.27)
				)
				(justify left bottom)
			)
		)
		(property "Value" "TPD1E0B04_XDFN-2"
			(at 403.86 228.6 0)
			(effects
				(font
					(size 1.27 1.27)
					(thickness 0.15)
				)
				(justify left bottom)
				(hide yes)
			)
		)
		(property "Footprint" "antmicro-footprints:XDFN-2_1x0.60mm"
			(at 403.86 223.52 0)
			(effects
				(font
					(size 1.27 1.27)
					(thickness 0.15)
				)
				(justify left bottom)
				(hide yes)
			)
		)
		(property "Datasheet" "https://www.ti.com/general/docs/suppproductinfo.tsp?distId=26&gotoUrl=https://www.ti.com/lit/gpn/tpd1e0b04"
			(at 403.86 226.06 0)
			(effects
				(font
					(size 1.27 1.27)
					(thickness 0.15)
				)
				(justify left bottom)
				(hide yes)
			)
		)
		(property "Description" ""
			(at 388.62 218.44 0)
			(effects
				(font
					(size 1.27 1.27)
				)
				(hide yes)
			)
		)
		(property "Manufacturer" "Texas Instruments"
			(at 403.86 231.14 0)
			(effects
				(font
					(size 1.27 1.27)
					(thickness 0.15)
				)
				(justify left bottom)
				(hide yes)
			)
		)
		(property "MPN" "TPD1E0B04DPYR"
			(at 373.38 217.805 0)
			(effects
				(font
					(size 1.27 1.27)
					(thickness 0.15)
				)
				(justify left bottom)
			)
		)
		(property "Author" "Antmicro"
			(at 403.86 233.68 0)
			(effects
				(font
					(size 1.27 1.27)
					(thickness 0.15)
				)
				(justify left bottom)
				(hide yes)
			)
		)
		(property "License" "Apache-2.0"
			(at 403.86 236.22 0)
			(effects
				(font
					(size 1.27 1.27)
					(thickness 0.15)
				)
				(justify left bottom)
				(hide yes)
			)
		)
		(pin "1"
		)
		(pin "2"
		)
		(instances
			(project "jetson-orin-baseboard"
				(path ""
					(reference "D49")
					(unit 1)
				)
			)
		)
	)
	(symbol
		(lib_id "antmicroTVSDiodes:TPD1E0B04_XDFN-2")
		(at 261.62 241.3 90)
		(unit 1)
		(exclude_from_sim no)
		(in_bom yes)
		(on_board yes)
		(dnp no)
		(property "Reference" "D58"
			(at 259.715 237.49 90)
			(effects
				(font
					(size 1.27 1.27)
				)
				(justify left)
			)
		)
		(property "Value" "TPD1E0B04_XDFN-2"
			(at 271.78 226.06 0)
			(effects
				(font
					(size 1.27 1.27)
					(thickness 0.15)
				)
				(justify left bottom)
				(hide yes)
			)
		)
		(property "Footprint" "antmicro-footprints:XDFN-2_1x0.60mm"
			(at 266.7 226.06 0)
			(effects
				(font
					(size 1.27 1.27)
					(thickness 0.15)
				)
				(justify left bottom)
				(hide yes)
			)
		)
		(property "Datasheet" "https://www.ti.com/general/docs/suppproductinfo.tsp?distId=26&gotoUrl=https://www.ti.com/lit/gpn/tpd1e0b04"
			(at 269.24 226.06 0)
			(effects
				(font
					(size 1.27 1.27)
					(thickness 0.15)
				)
				(justify left bottom)
				(hide yes)
			)
		)
		(property "Description" ""
			(at 261.62 241.3 0)
			(effects
				(font
					(size 1.27 1.27)
				)
				(hide yes)
			)
		)
		(property "Manufacturer" "Texas Instruments"
			(at 274.32 226.06 0)
			(effects
				(font
					(size 1.27 1.27)
					(thickness 0.15)
				)
				(justify left bottom)
				(hide yes)
			)
		)
		(property "MPN" "TPD1E0B04DPYR"
			(at 259.715 240.03 90)
			(effects
				(font
					(size 1.27 1.27)
					(thickness 0.15)
				)
				(justify left)
			)
		)
		(property "Author" "Antmicro"
			(at 276.86 226.06 0)
			(effects
				(font
					(size 1.27 1.27)
					(thickness 0.15)
				)
				(justify left bottom)
				(hide yes)
			)
		)
		(property "License" "Apache-2.0"
			(at 279.4 226.06 0)
			(effects
				(font
					(size 1.27 1.27)
					(thickness 0.15)
				)
				(justify left bottom)
				(hide yes)
			)
		)
		(pin "1"
		)
		(pin "2"
		)
		(instances
			(project "jetson-orin-baseboard"
				(path ""
					(reference "D58")
					(unit 1)
				)
			)
		)
	)
	(symbol
		(lib_id "antmicroCapacitors0402:C_100n_0402")
		(at 62.23 156.21 270)
		(mirror x)
		(unit 1)
		(exclude_from_sim no)
		(in_bom yes)
		(on_board yes)
		(dnp no)
		(property "Reference" "C48"
			(at 64.135 152.4 90)
			(effects
				(font
					(size 1.27 1.27)
				)
				(justify left)
			)
		)
		(property "Value" "C_100n_0402"
			(at 52.07 135.89 0)
			(effects
				(font
					(size 1.27 1.27)
					(thickness 0.15)
				)
				(justify left bottom)
				(hide yes)
			)
		)
		(property "Footprint" "antmicro-footprints:C_0402_1005Metric"
			(at 49.53 135.89 0)
			(effects
				(font
					(size 1.27 1.27)
					(thickness 0.15)
				)
				(justify left bottom)
				(hide yes)
			)
		)
		(property "Datasheet" "https://www.murata.com/products/productdetail?partno=GRM155R61H104KE14%23"
			(at 46.99 135.89 0)
			(effects
				(font
					(size 1.27 1.27)
					(thickness 0.15)
				)
				(justify left bottom)
				(hide yes)
			)
		)
		(property "Description" ""
			(at 62.23 156.21 0)
			(effects
				(font
					(size 1.27 1.27)
				)
				(hide yes)
			)
		)
		(property "Manufacturer" "Murata"
			(at 41.91 135.89 0)
			(effects
				(font
					(size 1.27 1.27)
					(thickness 0.15)
				)
				(justify left bottom)
				(hide yes)
			)
		)
		(property "MPN" "GRM155R61H104KE14D"
			(at 44.45 135.89 0)
			(effects
				(font
					(size 1.27 1.27)
					(thickness 0.15)
				)
				(justify left bottom)
				(hide yes)
			)
		)
		(property "Val" "100n"
			(at 64.135 154.94 90)
			(effects
				(font
					(size 1.27 1.27)
					(thickness 0.15)
				)
				(justify left)
			)
		)
		(property "License" "Apache-2.0"
			(at 39.37 135.89 0)
			(effects
				(font
					(size 1.27 1.27)
					(thickness 0.15)
				)
				(justify left bottom)
				(hide yes)
			)
		)
		(property "Author" "Antmicro"
			(at 36.83 135.89 0)
			(effects
				(font
					(size 1.27 1.27)
					(thickness 0.15)
				)
				(justify left bottom)
				(hide yes)
			)
		)
		(property "Voltage" "50V"
			(at 34.29 135.89 0)
			(effects
				(font
					(size 1.27 1.27)
				)
				(justify left bottom)
				(hide yes)
			)
		)
		(property "Dielectric" "X5R"
			(at 31.75 135.89 0)
			(effects
				(font
					(size 1.27 1.27)
				)
				(justify left bottom)
				(hide yes)
			)
		)
		(pin "1"
		)
		(pin "2"
		)
		(instances
			(project "jetson-orin-baseboard"
				(path ""
					(reference "C48")
					(unit 1)
				)
			)
		)
	)
	(symbol
		(lib_id "antmicropower:GND")
		(at 185.42 97.79 0)
		(unit 1)
		(exclude_from_sim no)
		(in_bom yes)
		(on_board yes)
		(dnp no)
		(fields_autoplaced yes)
		(property "Reference" "#PWR0207"
			(at 185.42 104.14 0)
			(effects
				(font
					(size 1.27 1.27)
				)
				(justify left bottom)
				(hide yes)
			)
		)
		(property "Value" "GND"
			(at 185.42 101.6 0)
			(effects
				(font
					(size 1.27 1.27)
					(thickness 0.15)
				)
			)
		)
		(property "Footprint" ""
			(at 194.31 105.41 0)
			(effects
				(font
					(size 1.27 1.27)
					(thickness 0.15)
				)
				(justify left bottom)
				(hide yes)
			)
		)
		(property "Datasheet" ""
			(at 194.31 110.49 0)
			(effects
				(font
					(size 1.27 1.27)
					(thickness 0.15)
				)
				(justify left bottom)
				(hide yes)
			)
		)
		(property "Description" ""
			(at 185.42 97.79 0)
			(effects
				(font
					(size 1.27 1.27)
				)
				(hide yes)
			)
		)
		(property "Author" "Antmicro"
			(at 194.31 105.41 0)
			(effects
				(font
					(size 1.27 1.27)
					(thickness 0.15)
				)
				(justify left bottom)
				(hide yes)
			)
		)
		(property "License" "Apache-2.0"
			(at 194.31 107.95 0)
			(effects
				(font
					(size 1.27 1.27)
					(thickness 0.15)
				)
				(justify left bottom)
				(hide yes)
			)
		)
		(pin "1"
		)
		(instances
			(project "jetson-orin-baseboard"
				(path ""
					(reference "#PWR0207")
					(unit 1)
				)
			)
		)
	)
	(symbol
		(lib_id "antmicropower:+1V8")
		(at 261.62 254 0)
		(unit 1)
		(exclude_from_sim no)
		(in_bom yes)
		(on_board yes)
		(dnp no)
		(property "Reference" "#PWR0243"
			(at 261.62 257.81 0)
			(effects
				(font
					(size 1.27 1.27)
				)
				(justify left bottom)
				(hide yes)
			)
		)
		(property "Value" "+1V8"
			(at 258.445 250.19 0)
			(effects
				(font
					(size 1.27 1.27)
					(thickness 0.15)
				)
				(justify left)
			)
		)
		(property "Footprint" ""
			(at 276.86 261.62 0)
			(effects
				(font
					(size 1.27 1.27)
					(thickness 0.15)
				)
				(justify left bottom)
				(hide yes)
			)
		)
		(property "Datasheet" ""
			(at 276.86 264.16 0)
			(effects
				(font
					(size 1.27 1.27)
					(thickness 0.15)
				)
				(justify left bottom)
				(hide yes)
			)
		)
		(property "Description" ""
			(at 261.62 254 0)
			(effects
				(font
					(size 1.27 1.27)
				)
				(hide yes)
			)
		)
		(property "Author" "Antmicro"
			(at 276.86 259.08 0)
			(effects
				(font
					(size 1.27 1.27)
					(thickness 0.15)
				)
				(justify left bottom)
				(hide yes)
			)
		)
		(property "License" "Apache-2.0"
			(at 276.86 261.62 0)
			(effects
				(font
					(size 1.27 1.27)
					(thickness 0.15)
				)
				(justify left bottom)
				(hide yes)
			)
		)
		(pin "1"
		)
		(instances
			(project "jetson-orin-baseboard"
				(path ""
					(reference "#PWR0243")
					(unit 1)
				)
			)
		)
	)
	(symbol
		(lib_id "antmicropower:+5V")
		(at 62.23 148.59 0)
		(unit 1)
		(exclude_from_sim no)
		(in_bom yes)
		(on_board yes)
		(dnp no)
		(property "Reference" "#PWR0172"
			(at 62.23 152.4 0)
			(effects
				(font
					(size 1.27 1.27)
				)
				(justify left bottom)
				(hide yes)
			)
		)
		(property "Value" "+5V"
			(at 60.325 145.415 0)
			(effects
				(font
					(size 1.27 1.27)
					(thickness 0.15)
				)
				(justify left bottom)
			)
		)
		(property "Footprint" ""
			(at 77.47 156.21 0)
			(effects
				(font
					(size 1.27 1.27)
					(thickness 0.15)
				)
				(justify left bottom)
				(hide yes)
			)
		)
		(property "Datasheet" ""
			(at 77.47 158.75 0)
			(effects
				(font
					(size 1.27 1.27)
					(thickness 0.15)
				)
				(justify left bottom)
				(hide yes)
			)
		)
		(property "Description" ""
			(at 62.23 148.59 0)
			(effects
				(font
					(size 1.27 1.27)
				)
				(hide yes)
			)
		)
		(property "Author" "Antmicro"
			(at 77.47 156.21 0)
			(effects
				(font
					(size 1.27 1.27)
					(thickness 0.15)
				)
				(justify left bottom)
				(hide yes)
			)
		)
		(property "License" "Apache-2.0"
			(at 77.47 158.75 0)
			(effects
				(font
					(size 1.27 1.27)
					(thickness 0.15)
				)
				(justify left bottom)
				(hide yes)
			)
		)
		(pin "1"
		)
		(instances
			(project "jetson-orin-baseboard"
				(path ""
					(reference "#PWR0172")
					(unit 1)
				)
			)
		)
	)
	(symbol
		(lib_id "antmicroWire2BoardConnectors:Molex_PicoBlade_1x4_0533980471")
		(at 76.2 173.99 0)
		(mirror x)
		(unit 1)
		(exclude_from_sim no)
		(in_bom yes)
		(on_board yes)
		(dnp no)
		(fields_autoplaced yes)
		(property "Reference" "J10"
			(at 81.28 154.94 0)
			(effects
				(font
					(size 1.27 1.27)
					(thickness 0.15)
				)
			)
		)
		(property "Value" "Molex_PicoBlade_1x4_0533980471"
			(at 96.52 166.37 0)
			(effects
				(font
					(size 1.27 1.27)
					(thickness 0.15)
				)
				(justify left bottom)
				(hide yes)
			)
		)
		(property "Footprint" "antmicro-footprints:Conn_Molex_PicoBlade_1x4_0533980471"
			(at 96.52 163.83 0)
			(effects
				(font
					(size 1.27 1.27)
					(thickness 0.15)
				)
				(justify left bottom)
				(hide yes)
			)
		)
		(property "Datasheet" "https://www.molex.com/molex/products/part-detail/pcb_headers/0533980471"
			(at 96.52 161.29 0)
			(effects
				(font
					(size 1.27 1.27)
					(thickness 0.15)
				)
				(justify left bottom)
				(hide yes)
			)
		)
		(property "Description" ""
			(at 76.2 173.99 0)
			(effects
				(font
					(size 1.27 1.27)
				)
				(hide yes)
			)
		)
		(property "MPN" "0533980471"
			(at 81.28 157.48 0)
			(effects
				(font
					(size 1.27 1.27)
					(thickness 0.15)
				)
			)
		)
		(property "Manufacturer" "Molex"
			(at 96.52 158.75 0)
			(effects
				(font
					(size 1.27 1.27)
					(thickness 0.15)
				)
				(justify left bottom)
				(hide yes)
			)
		)
		(property "Author" "Antmicro"
			(at 96.52 153.67 0)
			(effects
				(font
					(size 1.27 1.27)
					(thickness 0.15)
				)
				(justify left bottom)
				(hide yes)
			)
		)
		(property "License" "Apache-2.0"
			(at 96.52 151.13 0)
			(effects
				(font
					(size 1.27 1.27)
					(thickness 0.15)
				)
				(justify left bottom)
				(hide yes)
			)
		)
		(pin "1"
		)
		(pin "2"
		)
		(pin "3"
		)
		(pin "4"
		)
		(pin "MP1"
		)
		(pin "MP2"
		)
		(instances
			(project "jetson-orin-baseboard"
				(path ""
					(reference "J10")
					(unit 1)
				)
			)
		)
	)
	(symbol
		(lib_id "antmicroResistors0402:R_0R_0402")
		(at 44.45 82.55 270)
		(unit 1)
		(exclude_from_sim no)
		(in_bom yes)
		(on_board yes)
		(dnp no)
		(property "Reference" "R217"
			(at 45.72 83.82 90)
			(effects
				(font
					(size 1.27 1.27)
				)
				(justify left)
			)
		)
		(property "Value" "R_0R_0402"
			(at 31.75 102.87 0)
			(effects
				(font
					(size 1.27 1.27)
					(thickness 0.15)
				)
				(justify left bottom)
				(hide yes)
			)
		)
		(property "Footprint" "antmicro-footprints:R_0402_1005Metric"
			(at 29.21 102.87 0)
			(effects
				(font
					(size 1.27 1.27)
					(thickness 0.15)
				)
				(justify left bottom)
				(hide yes)
			)
		)
		(property "Datasheet" "https://industrial.panasonic.com/cdbs/www-data/pdf/RDA0000/AOA0000C301.pdf"
			(at 26.67 102.87 0)
			(effects
				(font
					(size 1.27 1.27)
					(thickness 0.15)
				)
				(justify left bottom)
				(hide yes)
			)
		)
		(property "Description" ""
			(at 44.45 82.55 0)
			(effects
				(font
					(size 1.27 1.27)
				)
				(hide yes)
			)
		)
		(property "Manufacturer" "Panasonic"
			(at 21.59 102.87 0)
			(effects
				(font
					(size 1.27 1.27)
					(thickness 0.15)
				)
				(justify left bottom)
				(hide yes)
			)
		)
		(property "MPN" "ERJ2GE0R00X"
			(at 24.13 102.87 0)
			(effects
				(font
					(size 1.27 1.27)
					(thickness 0.15)
				)
				(justify left bottom)
				(hide yes)
			)
		)
		(property "Val" "0R"
			(at 45.72 86.36 90)
			(effects
				(font
					(size 1.27 1.27)
					(thickness 0.15)
				)
				(justify left)
			)
		)
		(property "License" "Apache-2.0"
			(at 19.05 102.87 0)
			(effects
				(font
					(size 1.27 1.27)
					(thickness 0.15)
				)
				(justify left bottom)
				(hide yes)
			)
		)
		(property "Author" "Antmicro"
			(at 16.51 102.87 0)
			(effects
				(font
					(size 1.27 1.27)
					(thickness 0.15)
				)
				(justify left bottom)
				(hide yes)
			)
		)
		(property "Tolerance" "~"
			(at 34.29 102.87 0)
			(effects
				(font
					(size 1.27 1.27)
				)
				(justify left bottom)
				(hide yes)
			)
		)
		(property "Current" "1A"
			(at 13.97 102.87 0)
			(effects
				(font
					(size 1.27 1.27)
					(thickness 0.15)
				)
				(justify left bottom)
				(hide yes)
			)
		)
		(pin "1"
		)
		(pin "2"
		)
		(instances
			(project "jetson-orin-baseboard"
				(path ""
					(reference "R217")
					(unit 1)
				)
			)
		)
	)
	(symbol
		(lib_id "antmicropower:GND")
		(at 398.78 246.38 0)
		(unit 1)
		(exclude_from_sim no)
		(in_bom yes)
		(on_board yes)
		(dnp no)
		(fields_autoplaced yes)
		(property "Reference" "#PWR0173"
			(at 398.78 252.73 0)
			(effects
				(font
					(size 1.27 1.27)
				)
				(justify left bottom)
				(hide yes)
			)
		)
		(property "Value" "GND"
			(at 398.78 250.19 0)
			(effects
				(font
					(size 1.27 1.27)
					(thickness 0.15)
				)
			)
		)
		(property "Footprint" ""
			(at 407.67 254 0)
			(effects
				(font
					(size 1.27 1.27)
					(thickness 0.15)
				)
				(justify left bottom)
				(hide yes)
			)
		)
		(property "Datasheet" ""
			(at 407.67 259.08 0)
			(effects
				(font
					(size 1.27 1.27)
					(thickness 0.15)
				)
				(justify left bottom)
				(hide yes)
			)
		)
		(property "Description" ""
			(at 398.78 246.38 0)
			(effects
				(font
					(size 1.27 1.27)
				)
				(hide yes)
			)
		)
		(property "Author" "Antmicro"
			(at 407.67 254 0)
			(effects
				(font
					(size 1.27 1.27)
					(thickness 0.15)
				)
				(justify left bottom)
				(hide yes)
			)
		)
		(property "License" "Apache-2.0"
			(at 407.67 256.54 0)
			(effects
				(font
					(size 1.27 1.27)
					(thickness 0.15)
				)
				(justify left bottom)
				(hide yes)
			)
		)
		(pin "1"
		)
		(instances
			(project "jetson-orin-baseboard"
				(path ""
					(reference "#PWR0173")
					(unit 1)
				)
			)
		)
	)
	(symbol
		(lib_id "antmicroCapacitors0402:C_100n_0402")
		(at 152.4 35.56 90)
		(mirror x)
		(unit 1)
		(exclude_from_sim no)
		(in_bom yes)
		(on_board yes)
		(dnp no)
		(property "Reference" "C130"
			(at 154.305 36.83 90)
			(effects
				(font
					(size 1.27 1.27)
				)
				(justify right)
			)
		)
		(property "Value" "C_100n_0402"
			(at 162.56 55.88 0)
			(effects
				(font
					(size 1.27 1.27)
					(thickness 0.15)
				)
				(justify left bottom)
				(hide yes)
			)
		)
		(property "Footprint" "antmicro-footprints:C_0402_1005Metric"
			(at 165.1 55.88 0)
			(effects
				(font
					(size 1.27 1.27)
					(thickness 0.15)
				)
				(justify left bottom)
				(hide yes)
			)
		)
		(property "Datasheet" "https://www.murata.com/products/productdetail?partno=GRM155R61H104KE14%23"
			(at 167.64 55.88 0)
			(effects
				(font
					(size 1.27 1.27)
					(thickness 0.15)
				)
				(justify left bottom)
				(hide yes)
			)
		)
		(property "Description" ""
			(at 152.4 35.56 0)
			(effects
				(font
					(size 1.27 1.27)
				)
				(hide yes)
			)
		)
		(property "Manufacturer" "Murata"
			(at 172.72 55.88 0)
			(effects
				(font
					(size 1.27 1.27)
					(thickness 0.15)
				)
				(justify left bottom)
				(hide yes)
			)
		)
		(property "MPN" "GRM155R61H104KE14D"
			(at 170.18 55.88 0)
			(effects
				(font
					(size 1.27 1.27)
					(thickness 0.15)
				)
				(justify left bottom)
				(hide yes)
			)
		)
		(property "Val" "100n"
			(at 154.305 39.37 90)
			(effects
				(font
					(size 1.27 1.27)
					(thickness 0.15)
				)
				(justify right)
			)
		)
		(property "License" "Apache-2.0"
			(at 175.26 55.88 0)
			(effects
				(font
					(size 1.27 1.27)
					(thickness 0.15)
				)
				(justify left bottom)
				(hide yes)
			)
		)
		(property "Author" "Antmicro"
			(at 177.8 55.88 0)
			(effects
				(font
					(size 1.27 1.27)
					(thickness 0.15)
				)
				(justify left bottom)
				(hide yes)
			)
		)
		(property "Voltage" "50V"
			(at 180.34 55.88 0)
			(effects
				(font
					(size 1.27 1.27)
				)
				(justify left bottom)
				(hide yes)
			)
		)
		(property "Dielectric" "X5R"
			(at 182.88 55.88 0)
			(effects
				(font
					(size 1.27 1.27)
				)
				(justify left bottom)
				(hide yes)
			)
		)
		(pin "1"
		)
		(pin "2"
		)
		(instances
			(project "jetson-orin-baseboard"
				(path ""
					(reference "C130")
					(unit 1)
				)
			)
		)
	)
	(symbol
		(lib_id "antmicroResistorNetworksArrays:R_4x330R_0402_array")
		(at 132.08 156.21 0)
		(mirror y)
		(unit 1)
		(exclude_from_sim no)
		(in_bom yes)
		(on_board yes)
		(dnp no)
		(property "Reference" "R53"
			(at 127 150.495 0)
			(effects
				(font
					(size 1.27 1.27)
				)
			)
		)
		(property "Value" "R_4x330R_0402_array"
			(at 105.41 161.29 0)
			(effects
				(font
					(size 1.27 1.27)
					(thickness 0.15)
				)
				(justify left bottom)
				(hide yes)
			)
		)
		(property "Footprint" "antmicro-footprints:R_Array_4x0402"
			(at 105.41 166.37 0)
			(effects
				(font
					(size 1.27 1.27)
					(thickness 0.15)
				)
				(justify left bottom)
				(hide yes)
			)
		)
		(property "Datasheet" "http://industrial.panasonic.com/cdbs/www-data/pdf/AOC0000/AOC0000C14.pdf"
			(at 105.41 168.91 0)
			(effects
				(font
					(size 1.27 1.27)
					(thickness 0.15)
				)
				(justify left bottom)
				(hide yes)
			)
		)
		(property "Description" ""
			(at 132.08 156.21 0)
			(effects
				(font
					(size 1.27 1.27)
				)
				(hide yes)
			)
		)
		(property "MPN" "EXB-28V331JX"
			(at 105.41 171.45 0)
			(effects
				(font
					(size 1.27 1.27)
					(thickness 0.15)
				)
				(justify left bottom)
				(hide yes)
			)
		)
		(property "Manufacturer" "Panasonic"
			(at 105.41 173.99 0)
			(effects
				(font
					(size 1.27 1.27)
					(thickness 0.15)
				)
				(justify left bottom)
				(hide yes)
			)
		)
		(property "Author" "Antmicro"
			(at 105.41 176.53 0)
			(effects
				(font
					(size 1.27 1.27)
					(thickness 0.15)
				)
				(justify left bottom)
				(hide yes)
			)
		)
		(property "License" "Apache-2.0"
			(at 105.41 179.07 0)
			(effects
				(font
					(size 1.27 1.27)
					(thickness 0.15)
				)
				(justify left bottom)
				(hide yes)
			)
		)
		(property "Val" "R_4x330R_0402"
			(at 127 153.035 0)
			(effects
				(font
					(size 1.27 1.27)
				)
			)
		)
		(pin "1"
		)
		(pin "2"
		)
		(pin "3"
		)
		(pin "4"
		)
		(pin "5"
		)
		(pin "6"
		)
		(pin "7"
		)
		(pin "8"
		)
		(instances
			(project "jetson-orin-baseboard"
				(path ""
					(reference "R53")
					(unit 1)
				)
			)
		)
	)
	(symbol
		(lib_id "antmicropower:GND")
		(at 204.47 62.23 0)
		(unit 1)
		(exclude_from_sim no)
		(in_bom yes)
		(on_board yes)
		(dnp no)
		(fields_autoplaced yes)
		(property "Reference" "#PWR0184"
			(at 204.47 68.58 0)
			(effects
				(font
					(size 1.27 1.27)
				)
				(justify left bottom)
				(hide yes)
			)
		)
		(property "Value" "GND"
			(at 204.47 66.04 0)
			(effects
				(font
					(size 1.27 1.27)
					(thickness 0.15)
				)
			)
		)
		(property "Footprint" ""
			(at 213.36 69.85 0)
			(effects
				(font
					(size 1.27 1.27)
					(thickness 0.15)
				)
				(justify left bottom)
				(hide yes)
			)
		)
		(property "Datasheet" ""
			(at 213.36 74.93 0)
			(effects
				(font
					(size 1.27 1.27)
					(thickness 0.15)
				)
				(justify left bottom)
				(hide yes)
			)
		)
		(property "Description" ""
			(at 204.47 62.23 0)
			(effects
				(font
					(size 1.27 1.27)
				)
				(hide yes)
			)
		)
		(property "Author" "Antmicro"
			(at 213.36 69.85 0)
			(effects
				(font
					(size 1.27 1.27)
					(thickness 0.15)
				)
				(justify left bottom)
				(hide yes)
			)
		)
		(property "License" "Apache-2.0"
			(at 213.36 72.39 0)
			(effects
				(font
					(size 1.27 1.27)
					(thickness 0.15)
				)
				(justify left bottom)
				(hide yes)
			)
		)
		(pin "1"
		)
		(instances
			(project "jetson-orin-baseboard"
				(path ""
					(reference "#PWR0184")
					(unit 1)
				)
			)
		)
	)
	(symbol
		(lib_id "antmicroCapacitors0402:C_1u_0402")
		(at 295.91 185.42 90)
		(unit 1)
		(exclude_from_sim no)
		(in_bom yes)
		(on_board yes)
		(dnp no)
		(property "Reference" "C106"
			(at 297.815 181.61 90)
			(effects
				(font
					(size 1.27 1.27)
				)
				(justify right)
			)
		)
		(property "Value" "C_1u_0402"
			(at 306.07 165.1 0)
			(effects
				(font
					(size 1.27 1.27)
					(thickness 0.15)
				)
				(justify left bottom)
				(hide yes)
			)
		)
		(property "Footprint" "antmicro-footprints:C_0402_1005Metric"
			(at 308.61 165.1 0)
			(effects
				(font
					(size 1.27 1.27)
					(thickness 0.15)
				)
				(justify left bottom)
				(hide yes)
			)
		)
		(property "Datasheet" "https://product.tdk.com/en/search/capacitor/ceramic/mlcc/info?part_no=C1005X6S1A105K050BC"
			(at 311.15 165.1 0)
			(effects
				(font
					(size 1.27 1.27)
					(thickness 0.15)
				)
				(justify left bottom)
				(hide yes)
			)
		)
		(property "Description" ""
			(at 295.91 185.42 0)
			(effects
				(font
					(size 1.27 1.27)
				)
				(hide yes)
			)
		)
		(property "Manufacturer" "TDK"
			(at 316.23 165.1 0)
			(effects
				(font
					(size 1.27 1.27)
					(thickness 0.15)
				)
				(justify left bottom)
				(hide yes)
			)
		)
		(property "MPN" "C1005X6S1A105K050BC"
			(at 313.69 165.1 0)
			(effects
				(font
					(size 1.27 1.27)
					(thickness 0.15)
				)
				(justify left bottom)
				(hide yes)
			)
		)
		(property "Val" "1u"
			(at 297.815 184.15 90)
			(effects
				(font
					(size 1.27 1.27)
					(thickness 0.15)
				)
				(justify right)
			)
		)
		(property "License" "Apache-2.0"
			(at 318.77 165.1 0)
			(effects
				(font
					(size 1.27 1.27)
					(thickness 0.15)
				)
				(justify left bottom)
				(hide yes)
			)
		)
		(property "Author" "Antmicro"
			(at 321.31 165.1 0)
			(effects
				(font
					(size 1.27 1.27)
					(thickness 0.15)
				)
				(justify left bottom)
				(hide yes)
			)
		)
		(property "Voltage" ""
			(at 323.85 165.1 0)
			(effects
				(font
					(size 1.27 1.27)
				)
				(justify left bottom)
				(hide yes)
			)
		)
		(property "Dielectric" ""
			(at 326.39 165.1 0)
			(effects
				(font
					(size 1.27 1.27)
				)
				(justify left bottom)
				(hide yes)
			)
		)
		(pin "1"
		)
		(pin "2"
		)
		(instances
			(project "jetson-orin-baseboard"
				(path ""
					(reference "C106")
					(unit 1)
				)
			)
		)
	)
	(symbol
		(lib_id "antmicroTVSDiodes:TPD4E05U06QDQARQ1")
		(at 331.47 234.95 0)
		(unit 1)
		(exclude_from_sim no)
		(in_bom yes)
		(on_board yes)
		(dnp no)
		(fields_autoplaced yes)
		(property "Reference" "U30"
			(at 337.185 227.965 0)
			(effects
				(font
					(size 1.27 1.27)
				)
			)
		)
		(property "Value" "TPD4E05U06QDQARQ1"
			(at 355.6 245.11 0)
			(effects
				(font
					(size 1.27 1.27)
					(thickness 0.15)
				)
				(justify left bottom)
				(hide yes)
			)
		)
		(property "Footprint" "antmicro-footprints:USON-10_2.5x1mm_P0.5mm"
			(at 355.6 240.03 0)
			(effects
				(font
					(size 1.27 1.27)
					(thickness 0.15)
				)
				(justify left bottom)
				(hide yes)
			)
		)
		(property "Datasheet" "https://www.ti.com/lit/ds/symlink/tpd4e05u06-q1.pdf?HQS=dis-mous-null-mousermode-dsf-pf-null-wwe&ts=1663591265741&ref_url=https%253A%252F%252Fwww.mouser.com%252F"
			(at 355.6 242.57 0)
			(effects
				(font
					(size 1.27 1.27)
					(thickness 0.15)
				)
				(justify left bottom)
				(hide yes)
			)
		)
		(property "Description" ""
			(at 331.47 234.95 0)
			(effects
				(font
					(size 1.27 1.27)
				)
				(hide yes)
			)
		)
		(property "Manufacturer" "Texas Instruments"
			(at 355.6 247.65 0)
			(effects
				(font
					(size 1.27 1.27)
					(thickness 0.15)
				)
				(justify left bottom)
				(hide yes)
			)
		)
		(property "MPN" "TPD4E05U06QDQARQ1"
			(at 337.185 230.505 0)
			(effects
				(font
					(size 1.27 1.27)
					(thickness 0.15)
				)
			)
		)
		(property "Author" "Antmicro"
			(at 355.6 250.19 0)
			(effects
				(font
					(size 1.27 1.27)
					(thickness 0.15)
				)
				(justify left bottom)
				(hide yes)
			)
		)
		(property "License" "Apache-2.0"
			(at 355.6 252.73 0)
			(effects
				(font
					(size 1.27 1.27)
					(thickness 0.15)
				)
				(justify left bottom)
				(hide yes)
			)
		)
		(pin "1"
		)
		(pin "10"
		)
		(pin "2"
		)
		(pin "3"
		)
		(pin "4"
		)
		(pin "5"
		)
		(pin "6"
		)
		(pin "7"
		)
		(pin "8"
		)
		(pin "9"
		)
		(instances
			(project "jetson-orin-baseboard"
				(path ""
					(reference "U30")
					(unit 1)
				)
			)
		)
	)
	(symbol
		(lib_id "antmicroCapacitors0402:C_220n_0402")
		(at 285.75 48.26 180)
		(unit 1)
		(exclude_from_sim no)
		(in_bom yes)
		(on_board yes)
		(dnp no)
		(property "Reference" "C109"
			(at 284.48 47.625 0)
			(effects
				(font
					(size 1.27 1.27)
				)
				(justify right top)
			)
		)
		(property "Value" "C_220n_0402"
			(at 265.43 38.1 0)
			(effects
				(font
					(size 1.27 1.27)
					(thickness 0.15)
				)
				(justify left bottom)
				(hide yes)
			)
		)
		(property "Footprint" "antmicro-footprints:C_0402_1005Metric"
			(at 265.43 35.56 0)
			(effects
				(font
					(size 1.27 1.27)
					(thickness 0.15)
				)
				(justify left bottom)
				(hide yes)
			)
		)
		(property "Datasheet" "https://www.yageo.com/en/Chart/Download/pdf/CC0402KRX5R6BB224"
			(at 265.43 33.02 0)
			(effects
				(font
					(size 1.27 1.27)
					(thickness 0.15)
				)
				(justify left bottom)
				(hide yes)
			)
		)
		(property "Description" ""
			(at 285.75 48.26 0)
			(effects
				(font
					(size 1.27 1.27)
				)
				(hide yes)
			)
		)
		(property "Manufacturer" "YAGEO"
			(at 265.43 27.94 0)
			(effects
				(font
					(size 1.27 1.27)
					(thickness 0.15)
				)
				(justify left bottom)
				(hide yes)
			)
		)
		(property "MPN" "CC0402KRX5R6BB224"
			(at 265.43 30.48 0)
			(effects
				(font
					(size 1.27 1.27)
					(thickness 0.15)
				)
				(justify left bottom)
				(hide yes)
			)
		)
		(property "Val" "220n"
			(at 281.94 41.275 0)
			(effects
				(font
					(size 1.27 1.27)
					(thickness 0.15)
				)
				(justify left bottom)
			)
		)
		(property "License" "Apache-2.0"
			(at 265.43 25.4 0)
			(effects
				(font
					(size 1.27 1.27)
					(thickness 0.15)
				)
				(justify left bottom)
				(hide yes)
			)
		)
		(property "Author" "Antmicro"
			(at 265.43 22.86 0)
			(effects
				(font
					(size 1.27 1.27)
					(thickness 0.15)
				)
				(justify left bottom)
				(hide yes)
			)
		)
		(property "Voltage" ""
			(at 265.43 20.32 0)
			(effects
				(font
					(size 1.27 1.27)
				)
				(justify left bottom)
				(hide yes)
			)
		)
		(property "Dielectric" ""
			(at 265.43 17.78 0)
			(effects
				(font
					(size 1.27 1.27)
				)
				(justify left bottom)
				(hide yes)
			)
		)
		(pin "1"
		)
		(pin "2"
		)
		(instances
			(project "jetson-orin-baseboard"
				(path ""
					(reference "C109")
					(unit 1)
				)
			)
		)
	)
	(symbol
		(lib_id "antmicropower:GND")
		(at 217.17 92.71 0)
		(unit 1)
		(exclude_from_sim no)
		(in_bom yes)
		(on_board yes)
		(dnp no)
		(fields_autoplaced yes)
		(property "Reference" "#PWR0211"
			(at 217.17 99.06 0)
			(effects
				(font
					(size 1.27 1.27)
				)
				(justify left bottom)
				(hide yes)
			)
		)
		(property "Value" "GND"
			(at 217.17 96.52 0)
			(effects
				(font
					(size 1.27 1.27)
					(thickness 0.15)
				)
			)
		)
		(property "Footprint" ""
			(at 226.06 100.33 0)
			(effects
				(font
					(size 1.27 1.27)
					(thickness 0.15)
				)
				(justify left bottom)
				(hide yes)
			)
		)
		(property "Datasheet" ""
			(at 226.06 105.41 0)
			(effects
				(font
					(size 1.27 1.27)
					(thickness 0.15)
				)
				(justify left bottom)
				(hide yes)
			)
		)
		(property "Description" ""
			(at 217.17 92.71 0)
			(effects
				(font
					(size 1.27 1.27)
				)
				(hide yes)
			)
		)
		(property "Author" "Antmicro"
			(at 226.06 100.33 0)
			(effects
				(font
					(size 1.27 1.27)
					(thickness 0.15)
				)
				(justify left bottom)
				(hide yes)
			)
		)
		(property "License" "Apache-2.0"
			(at 226.06 102.87 0)
			(effects
				(font
					(size 1.27 1.27)
					(thickness 0.15)
				)
				(justify left bottom)
				(hide yes)
			)
		)
		(pin "1"
		)
		(instances
			(project "jetson-orin-baseboard"
				(path ""
					(reference "#PWR0211")
					(unit 1)
				)
			)
		)
	)
	(symbol
		(lib_id "antmicroTVSDiodes:TPD1E0B04_XDFN-2")
		(at 388.62 233.68 0)
		(unit 1)
		(exclude_from_sim no)
		(in_bom yes)
		(on_board yes)
		(dnp no)
		(property "Reference" "D17"
			(at 393.065 233.045 0)
			(effects
				(font
					(size 1.27 1.27)
				)
				(justify left bottom)
			)
		)
		(property "Value" "TPD1E0B04_XDFN-2"
			(at 403.86 243.84 0)
			(effects
				(font
					(size 1.27 1.27)
					(thickness 0.15)
				)
				(justify left bottom)
				(hide yes)
			)
		)
		(property "Footprint" "antmicro-footprints:XDFN-2_1x0.60mm"
			(at 403.86 238.76 0)
			(effects
				(font
					(size 1.27 1.27)
					(thickness 0.15)
				)
				(justify left bottom)
				(hide yes)
			)
		)
		(property "Datasheet" "https://www.ti.com/general/docs/suppproductinfo.tsp?distId=26&gotoUrl=https://www.ti.com/lit/gpn/tpd1e0b04"
			(at 403.86 241.3 0)
			(effects
				(font
					(size 1.27 1.27)
					(thickness 0.15)
				)
				(justify left bottom)
				(hide yes)
			)
		)
		(property "Description" ""
			(at 388.62 233.68 0)
			(effects
				(font
					(size 1.27 1.27)
				)
				(hide yes)
			)
		)
		(property "Manufacturer" "Texas Instruments"
			(at 403.86 246.38 0)
			(effects
				(font
					(size 1.27 1.27)
					(thickness 0.15)
				)
				(justify left bottom)
				(hide yes)
			)
		)
		(property "MPN" "TPD1E0B04DPYR"
			(at 373.38 233.045 0)
			(effects
				(font
					(size 1.27 1.27)
					(thickness 0.15)
				)
				(justify left bottom)
			)
		)
		(property "Author" "Antmicro"
			(at 403.86 248.92 0)
			(effects
				(font
					(size 1.27 1.27)
					(thickness 0.15)
				)
				(justify left bottom)
				(hide yes)
			)
		)
		(property "License" "Apache-2.0"
			(at 403.86 251.46 0)
			(effects
				(font
					(size 1.27 1.27)
					(thickness 0.15)
				)
				(justify left bottom)
				(hide yes)
			)
		)
		(pin "1"
		)
		(pin "2"
		)
		(instances
			(project "jetson-orin-baseboard"
				(path ""
					(reference "D17")
					(unit 1)
				)
			)
		)
	)
	(symbol
		(lib_id "antmicroTVSDiodes:TPD1E0B04_XDFN-2")
		(at 388.62 223.52 0)
		(unit 1)
		(exclude_from_sim no)
		(in_bom yes)
		(on_board yes)
		(dnp no)
		(property "Reference" "D50"
			(at 393.065 222.885 0)
			(effects
				(font
					(size 1.27 1.27)
				)
				(justify left bottom)
			)
		)
		(property "Value" "TPD1E0B04_XDFN-2"
			(at 403.86 233.68 0)
			(effects
				(font
					(size 1.27 1.27)
					(thickness 0.15)
				)
				(justify left bottom)
				(hide yes)
			)
		)
		(property "Footprint" "antmicro-footprints:XDFN-2_1x0.60mm"
			(at 403.86 228.6 0)
			(effects
				(font
					(size 1.27 1.27)
					(thickness 0.15)
				)
				(justify left bottom)
				(hide yes)
			)
		)
		(property "Datasheet" "https://www.ti.com/general/docs/suppproductinfo.tsp?distId=26&gotoUrl=https://www.ti.com/lit/gpn/tpd1e0b04"
			(at 403.86 231.14 0)
			(effects
				(font
					(size 1.27 1.27)
					(thickness 0.15)
				)
				(justify left bottom)
				(hide yes)
			)
		)
		(property "Description" ""
			(at 388.62 223.52 0)
			(effects
				(font
					(size 1.27 1.27)
				)
				(hide yes)
			)
		)
		(property "Manufacturer" "Texas Instruments"
			(at 403.86 236.22 0)
			(effects
				(font
					(size 1.27 1.27)
					(thickness 0.15)
				)
				(justify left bottom)
				(hide yes)
			)
		)
		(property "MPN" "TPD1E0B04DPYR"
			(at 373.38 222.885 0)
			(effects
				(font
					(size 1.27 1.27)
					(thickness 0.15)
				)
				(justify left bottom)
			)
		)
		(property "Author" "Antmicro"
			(at 403.86 238.76 0)
			(effects
				(font
					(size 1.27 1.27)
					(thickness 0.15)
				)
				(justify left bottom)
				(hide yes)
			)
		)
		(property "License" "Apache-2.0"
			(at 403.86 241.3 0)
			(effects
				(font
					(size 1.27 1.27)
					(thickness 0.15)
				)
				(justify left bottom)
				(hide yes)
			)
		)
		(pin "1"
		)
		(pin "2"
		)
		(instances
			(project "jetson-orin-baseboard"
				(path ""
					(reference "D50")
					(unit 1)
				)
			)
		)
	)
	(symbol
		(lib_id "antmicroTVSDiodes:TPD1E0B04_XDFN-2")
		(at 388.62 167.64 0)
		(unit 1)
		(exclude_from_sim no)
		(in_bom yes)
		(on_board yes)
		(dnp no)
		(property "Reference" "D39"
			(at 393.065 167.005 0)
			(effects
				(font
					(size 1.27 1.27)
				)
				(justify left bottom)
			)
		)
		(property "Value" "TPD1E0B04_XDFN-2"
			(at 403.86 177.8 0)
			(effects
				(font
					(size 1.27 1.27)
					(thickness 0.15)
				)
				(justify left bottom)
				(hide yes)
			)
		)
		(property "Footprint" "antmicro-footprints:XDFN-2_1x0.60mm"
			(at 403.86 172.72 0)
			(effects
				(font
					(size 1.27 1.27)
					(thickness 0.15)
				)
				(justify left bottom)
				(hide yes)
			)
		)
		(property "Datasheet" "https://www.ti.com/general/docs/suppproductinfo.tsp?distId=26&gotoUrl=https://www.ti.com/lit/gpn/tpd1e0b04"
			(at 403.86 175.26 0)
			(effects
				(font
					(size 1.27 1.27)
					(thickness 0.15)
				)
				(justify left bottom)
				(hide yes)
			)
		)
		(property "Description" ""
			(at 388.62 167.64 0)
			(effects
				(font
					(size 1.27 1.27)
				)
				(hide yes)
			)
		)
		(property "Manufacturer" "Texas Instruments"
			(at 403.86 180.34 0)
			(effects
				(font
					(size 1.27 1.27)
					(thickness 0.15)
				)
				(justify left bottom)
				(hide yes)
			)
		)
		(property "MPN" "TPD1E0B04DPYR"
			(at 373.38 167.005 0)
			(effects
				(font
					(size 1.27 1.27)
					(thickness 0.15)
				)
				(justify left bottom)
			)
		)
		(property "Author" "Antmicro"
			(at 403.86 182.88 0)
			(effects
				(font
					(size 1.27 1.27)
					(thickness 0.15)
				)
				(justify left bottom)
				(hide yes)
			)
		)
		(property "License" "Apache-2.0"
			(at 403.86 185.42 0)
			(effects
				(font
					(size 1.27 1.27)
					(thickness 0.15)
				)
				(justify left bottom)
				(hide yes)
			)
		)
		(pin "1"
		)
		(pin "2"
		)
		(instances
			(project "jetson-orin-baseboard"
				(path ""
					(reference "D39")
					(unit 1)
				)
			)
		)
	)
	(symbol
		(lib_id "antmicropower:+1V8")
		(at 295.91 167.64 0)
		(mirror y)
		(unit 1)
		(exclude_from_sim no)
		(in_bom yes)
		(on_board yes)
		(dnp no)
		(property "Reference" "#PWR0237"
			(at 295.91 171.45 0)
			(effects
				(font
					(size 1.27 1.27)
				)
				(justify left bottom)
				(hide yes)
			)
		)
		(property "Value" "+1V8"
			(at 297.815 164.465 0)
			(effects
				(font
					(size 1.27 1.27)
					(thickness 0.15)
				)
				(justify left bottom)
			)
		)
		(property "Footprint" ""
			(at 280.67 175.26 0)
			(effects
				(font
					(size 1.27 1.27)
					(thickness 0.15)
				)
				(justify left bottom)
				(hide yes)
			)
		)
		(property "Datasheet" ""
			(at 280.67 177.8 0)
			(effects
				(font
					(size 1.27 1.27)
					(thickness 0.15)
				)
				(justify left bottom)
				(hide yes)
			)
		)
		(property "Description" ""
			(at 295.91 167.64 0)
			(effects
				(font
					(size 1.27 1.27)
				)
				(hide yes)
			)
		)
		(property "Author" "Antmicro"
			(at 280.67 172.72 0)
			(effects
				(font
					(size 1.27 1.27)
					(thickness 0.15)
				)
				(justify left bottom)
				(hide yes)
			)
		)
		(property "License" "Apache-2.0"
			(at 280.67 175.26 0)
			(effects
				(font
					(size 1.27 1.27)
					(thickness 0.15)
				)
				(justify left bottom)
				(hide yes)
			)
		)
		(pin "1"
		)
		(instances
			(project "jetson-orin-baseboard"
				(path ""
					(reference "#PWR0237")
					(unit 1)
				)
			)
		)
	)
	(symbol
		(lib_id "antmicroTVSDiodes:TPD1E0B04_XDFN-2")
		(at 261.62 270.51 90)
		(unit 1)
		(exclude_from_sim no)
		(in_bom yes)
		(on_board yes)
		(dnp no)
		(property "Reference" "D59"
			(at 259.715 266.7 90)
			(effects
				(font
					(size 1.27 1.27)
				)
				(justify left)
			)
		)
		(property "Value" "TPD1E0B04_XDFN-2"
			(at 271.78 255.27 0)
			(effects
				(font
					(size 1.27 1.27)
					(thickness 0.15)
				)
				(justify left bottom)
				(hide yes)
			)
		)
		(property "Footprint" "antmicro-footprints:XDFN-2_1x0.60mm"
			(at 266.7 255.27 0)
			(effects
				(font
					(size 1.27 1.27)
					(thickness 0.15)
				)
				(justify left bottom)
				(hide yes)
			)
		)
		(property "Datasheet" "https://www.ti.com/general/docs/suppproductinfo.tsp?distId=26&gotoUrl=https://www.ti.com/lit/gpn/tpd1e0b04"
			(at 269.24 255.27 0)
			(effects
				(font
					(size 1.27 1.27)
					(thickness 0.15)
				)
				(justify left bottom)
				(hide yes)
			)
		)
		(property "Description" ""
			(at 261.62 270.51 0)
			(effects
				(font
					(size 1.27 1.27)
				)
				(hide yes)
			)
		)
		(property "Manufacturer" "Texas Instruments"
			(at 274.32 255.27 0)
			(effects
				(font
					(size 1.27 1.27)
					(thickness 0.15)
				)
				(justify left bottom)
				(hide yes)
			)
		)
		(property "MPN" "TPD1E0B04DPYR"
			(at 259.715 269.24 90)
			(effects
				(font
					(size 1.27 1.27)
					(thickness 0.15)
				)
				(justify left)
			)
		)
		(property "Author" "Antmicro"
			(at 276.86 255.27 0)
			(effects
				(font
					(size 1.27 1.27)
					(thickness 0.15)
				)
				(justify left bottom)
				(hide yes)
			)
		)
		(property "License" "Apache-2.0"
			(at 279.4 255.27 0)
			(effects
				(font
					(size 1.27 1.27)
					(thickness 0.15)
				)
				(justify left bottom)
				(hide yes)
			)
		)
		(pin "1"
		)
		(pin "2"
		)
		(instances
			(project "jetson-orin-baseboard"
				(path ""
					(reference "D59")
					(unit 1)
				)
			)
		)
	)
	(symbol
		(lib_id "antmicropower:+3V3")
		(at 152.4 33.02 0)
		(unit 1)
		(exclude_from_sim no)
		(in_bom yes)
		(on_board yes)
		(dnp no)
		(property "Reference" "#PWR0320"
			(at 152.4 36.83 0)
			(effects
				(font
					(size 1.27 1.27)
				)
				(justify left bottom)
				(hide yes)
			)
		)
		(property "Value" "+3V3"
			(at 149.225 29.21 0)
			(effects
				(font
					(size 1.27 1.27)
					(thickness 0.15)
				)
				(justify left)
			)
		)
		(property "Footprint" ""
			(at 167.64 40.64 0)
			(effects
				(font
					(size 1.27 1.27)
					(thickness 0.15)
				)
				(justify left bottom)
				(hide yes)
			)
		)
		(property "Datasheet" ""
			(at 167.64 43.18 0)
			(effects
				(font
					(size 1.27 1.27)
					(thickness 0.15)
				)
				(justify left bottom)
				(hide yes)
			)
		)
		(property "Description" ""
			(at 152.4 33.02 0)
			(effects
				(font
					(size 1.27 1.27)
				)
				(hide yes)
			)
		)
		(property "Author" "Antmicro"
			(at 167.64 35.56 0)
			(effects
				(font
					(size 1.27 1.27)
					(thickness 0.15)
				)
				(justify left bottom)
				(hide yes)
			)
		)
		(property "License" "Apache-2.0"
			(at 167.64 38.1 0)
			(effects
				(font
					(size 1.27 1.27)
					(thickness 0.15)
				)
				(justify left bottom)
				(hide yes)
			)
		)
		(pin "1"
		)
		(instances
			(project "jetson-orin-baseboard"
				(path ""
					(reference "#PWR0320")
					(unit 1)
				)
			)
		)
	)
	(symbol
		(lib_id "antmicroResistors0402:R_0R_0402")
		(at 344.17 114.3 0)
		(unit 1)
		(exclude_from_sim no)
		(in_bom no)
		(on_board yes)
		(dnp yes)
		(property "Reference" "R120"
			(at 349.25 113.665 0)
			(effects
				(font
					(size 1.27 1.27)
				)
				(justify left bottom)
			)
		)
		(property "Value" "R_0R_0402"
			(at 364.49 127 0)
			(effects
				(font
					(size 1.27 1.27)
					(thickness 0.15)
				)
				(justify left bottom)
				(hide yes)
			)
		)
		(property "Footprint" "antmicro-footprints:R_0402_1005Metric"
			(at 364.49 129.54 0)
			(effects
				(font
					(size 1.27 1.27)
					(thickness 0.15)
				)
				(justify left bottom)
				(hide yes)
			)
		)
		(property "Datasheet" "https://industrial.panasonic.com/cdbs/www-data/pdf/RDA0000/AOA0000C301.pdf"
			(at 364.49 132.08 0)
			(effects
				(font
					(size 1.27 1.27)
					(thickness 0.15)
				)
				(justify left bottom)
				(hide yes)
			)
		)
		(property "Description" ""
			(at 344.17 114.3 0)
			(effects
				(font
					(size 1.27 1.27)
				)
				(hide yes)
			)
		)
		(property "Manufacturer" "Panasonic"
			(at 364.49 137.16 0)
			(effects
				(font
					(size 1.27 1.27)
					(thickness 0.15)
				)
				(justify left bottom)
				(hide yes)
			)
		)
		(property "MPN" "ERJ2GE0R00X"
			(at 364.49 134.62 0)
			(effects
				(font
					(size 1.27 1.27)
					(thickness 0.15)
				)
				(justify left bottom)
				(hide yes)
			)
		)
		(property "Val" "0R"
			(at 341.63 113.665 0)
			(effects
				(font
					(size 1.27 1.27)
					(thickness 0.15)
				)
				(justify left bottom)
			)
		)
		(property "License" "Apache-2.0"
			(at 364.49 139.7 0)
			(effects
				(font
					(size 1.27 1.27)
					(thickness 0.15)
				)
				(justify left bottom)
				(hide yes)
			)
		)
		(property "Author" "Antmicro"
			(at 364.49 142.24 0)
			(effects
				(font
					(size 1.27 1.27)
					(thickness 0.15)
				)
				(justify left bottom)
				(hide yes)
			)
		)
		(property "Tolerance" "~"
			(at 364.49 124.46 0)
			(effects
				(font
					(size 1.27 1.27)
				)
				(justify left bottom)
				(hide yes)
			)
		)
		(property "Current" "1A"
			(at 364.49 144.78 0)
			(effects
				(font
					(size 1.27 1.27)
					(thickness 0.15)
				)
				(justify left bottom)
				(hide yes)
			)
		)
		(pin "1"
		)
		(pin "2"
		)
		(instances
			(project "jetson-orin-baseboard"
				(path ""
					(reference "R120")
					(unit 1)
				)
			)
		)
	)
	(symbol
		(lib_id "antmicropower:GND")
		(at 312.42 186.69 0)
		(unit 1)
		(exclude_from_sim no)
		(in_bom yes)
		(on_board yes)
		(dnp no)
		(fields_autoplaced yes)
		(property "Reference" "#PWR0245"
			(at 312.42 193.04 0)
			(effects
				(font
					(size 1.27 1.27)
				)
				(justify left bottom)
				(hide yes)
			)
		)
		(property "Value" "GND"
			(at 312.42 190.5 0)
			(effects
				(font
					(size 1.27 1.27)
					(thickness 0.15)
				)
			)
		)
		(property "Footprint" ""
			(at 321.31 194.31 0)
			(effects
				(font
					(size 1.27 1.27)
					(thickness 0.15)
				)
				(justify left bottom)
				(hide yes)
			)
		)
		(property "Datasheet" ""
			(at 321.31 199.39 0)
			(effects
				(font
					(size 1.27 1.27)
					(thickness 0.15)
				)
				(justify left bottom)
				(hide yes)
			)
		)
		(property "Description" ""
			(at 312.42 186.69 0)
			(effects
				(font
					(size 1.27 1.27)
				)
				(hide yes)
			)
		)
		(property "Author" "Antmicro"
			(at 321.31 194.31 0)
			(effects
				(font
					(size 1.27 1.27)
					(thickness 0.15)
				)
				(justify left bottom)
				(hide yes)
			)
		)
		(property "License" "Apache-2.0"
			(at 321.31 196.85 0)
			(effects
				(font
					(size 1.27 1.27)
					(thickness 0.15)
				)
				(justify left bottom)
				(hide yes)
			)
		)
		(pin "1"
		)
		(instances
			(project "jetson-orin-baseboard"
				(path ""
					(reference "#PWR0245")
					(unit 1)
				)
			)
		)
	)
	(symbol
		(lib_id "antmicropower:GND")
		(at 152.4 41.91 0)
		(unit 1)
		(exclude_from_sim no)
		(in_bom yes)
		(on_board yes)
		(dnp no)
		(fields_autoplaced yes)
		(property "Reference" "#PWR0217"
			(at 152.4 48.26 0)
			(effects
				(font
					(size 1.27 1.27)
				)
				(justify left bottom)
				(hide yes)
			)
		)
		(property "Value" "GND"
			(at 152.4 45.72 0)
			(effects
				(font
					(size 1.27 1.27)
					(thickness 0.15)
				)
			)
		)
		(property "Footprint" ""
			(at 161.29 49.53 0)
			(effects
				(font
					(size 1.27 1.27)
					(thickness 0.15)
				)
				(justify left bottom)
				(hide yes)
			)
		)
		(property "Datasheet" ""
			(at 161.29 54.61 0)
			(effects
				(font
					(size 1.27 1.27)
					(thickness 0.15)
				)
				(justify left bottom)
				(hide yes)
			)
		)
		(property "Description" ""
			(at 152.4 41.91 0)
			(effects
				(font
					(size 1.27 1.27)
				)
				(hide yes)
			)
		)
		(property "Author" "Antmicro"
			(at 161.29 49.53 0)
			(effects
				(font
					(size 1.27 1.27)
					(thickness 0.15)
				)
				(justify left bottom)
				(hide yes)
			)
		)
		(property "License" "Apache-2.0"
			(at 161.29 52.07 0)
			(effects
				(font
					(size 1.27 1.27)
					(thickness 0.15)
				)
				(justify left bottom)
				(hide yes)
			)
		)
		(pin "1"
		)
		(instances
			(project "jetson-orin-baseboard"
				(path ""
					(reference "#PWR0217")
					(unit 1)
				)
			)
		)
	)
	(symbol
		(lib_id "antmicropower:GND")
		(at 262.89 186.69 0)
		(unit 1)
		(exclude_from_sim no)
		(in_bom yes)
		(on_board yes)
		(dnp no)
		(fields_autoplaced yes)
		(property "Reference" "#PWR0321"
			(at 262.89 193.04 0)
			(effects
				(font
					(size 1.27 1.27)
				)
				(justify left bottom)
				(hide yes)
			)
		)
		(property "Value" "GND"
			(at 262.89 190.5 0)
			(effects
				(font
					(size 1.27 1.27)
					(thickness 0.15)
				)
			)
		)
		(property "Footprint" ""
			(at 271.78 194.31 0)
			(effects
				(font
					(size 1.27 1.27)
					(thickness 0.15)
				)
				(justify left bottom)
				(hide yes)
			)
		)
		(property "Datasheet" ""
			(at 271.78 199.39 0)
			(effects
				(font
					(size 1.27 1.27)
					(thickness 0.15)
				)
				(justify left bottom)
				(hide yes)
			)
		)
		(property "Description" ""
			(at 262.89 186.69 0)
			(effects
				(font
					(size 1.27 1.27)
				)
				(hide yes)
			)
		)
		(property "Author" "Antmicro"
			(at 271.78 194.31 0)
			(effects
				(font
					(size 1.27 1.27)
					(thickness 0.15)
				)
				(justify left bottom)
				(hide yes)
			)
		)
		(property "License" "Apache-2.0"
			(at 271.78 196.85 0)
			(effects
				(font
					(size 1.27 1.27)
					(thickness 0.15)
				)
				(justify left bottom)
				(hide yes)
			)
		)
		(pin "1"
		)
		(instances
			(project "jetson-orin-baseboard"
				(path ""
					(reference "#PWR0321")
					(unit 1)
				)
			)
		)
	)
	(symbol
		(lib_id "antmicropower:+3V3")
		(at 279.4 167.64 0)
		(unit 1)
		(exclude_from_sim no)
		(in_bom yes)
		(on_board yes)
		(dnp no)
		(property "Reference" "#PWR0236"
			(at 279.4 171.45 0)
			(effects
				(font
					(size 1.27 1.27)
				)
				(justify left bottom)
				(hide yes)
			)
		)
		(property "Value" "+3V3"
			(at 278.765 163.83 0)
			(effects
				(font
					(size 1.27 1.27)
					(thickness 0.15)
				)
			)
		)
		(property "Footprint" ""
			(at 294.64 175.26 0)
			(effects
				(font
					(size 1.27 1.27)
					(thickness 0.15)
				)
				(justify left bottom)
				(hide yes)
			)
		)
		(property "Datasheet" ""
			(at 294.64 177.8 0)
			(effects
				(font
					(size 1.27 1.27)
					(thickness 0.15)
				)
				(justify left bottom)
				(hide yes)
			)
		)
		(property "Description" ""
			(at 279.4 167.64 0)
			(effects
				(font
					(size 1.27 1.27)
				)
				(hide yes)
			)
		)
		(property "Author" "Antmicro"
			(at 294.64 170.18 0)
			(effects
				(font
					(size 1.27 1.27)
					(thickness 0.15)
				)
				(justify left bottom)
				(hide yes)
			)
		)
		(property "License" "Apache-2.0"
			(at 294.64 172.72 0)
			(effects
				(font
					(size 1.27 1.27)
					(thickness 0.15)
				)
				(justify left bottom)
				(hide yes)
			)
		)
		(pin "1"
		)
		(instances
			(project "jetson-orin-baseboard"
				(path ""
					(reference "#PWR0236")
					(unit 1)
				)
			)
		)
	)
	(symbol
		(lib_id "antmicroWire2BoardConnectors:JST_SH_1x4_SM04B-SRSS-TB-LF-SN")
		(at 218.44 81.28 0)
		(unit 1)
		(exclude_from_sim no)
		(in_bom yes)
		(on_board yes)
		(dnp no)
		(property "Reference" "J14"
			(at 222.25 77.47 0)
			(effects
				(font
					(size 1.27 1.27)
					(thickness 0.15)
				)
			)
		)
		(property "Value" "JST_SH_1x4_SM04B-SRSS-TB-LF-SN"
			(at 245.11 88.9 0)
			(effects
				(font
					(size 1.27 1.27)
					(thickness 0.15)
				)
				(justify left bottom)
				(hide yes)
			)
		)
		(property "Footprint" "antmicro-footprints:Conn_JST_SH_1x4_SM04B-SRSS-TB-LF-SN"
			(at 245.11 91.44 0)
			(effects
				(font
					(size 1.27 1.27)
					(thickness 0.15)
				)
				(justify left bottom)
				(hide yes)
			)
		)
		(property "Datasheet" "https://www.jst-mfg.com/product/pdf/eng/eSH.pdf"
			(at 245.11 93.98 0)
			(effects
				(font
					(size 1.27 1.27)
					(thickness 0.15)
				)
				(justify left bottom)
				(hide yes)
			)
		)
		(property "Description" ""
			(at 218.44 81.28 0)
			(effects
				(font
					(size 1.27 1.27)
				)
				(hide yes)
			)
		)
		(property "MPN" "SM04B-SRSS-TB(LF)(SN)"
			(at 225.425 86.36 90)
			(effects
				(font
					(size 1.27 1.27)
					(thickness 0.15)
				)
			)
		)
		(property "Manufacturer" "JST Automotive Connectors"
			(at 245.11 96.52 0)
			(effects
				(font
					(size 1.27 1.27)
					(thickness 0.15)
				)
				(justify left bottom)
				(hide yes)
			)
		)
		(property "Author" "Antmicro"
			(at 245.11 99.06 0)
			(effects
				(font
					(size 1.27 1.27)
					(thickness 0.15)
				)
				(justify left bottom)
				(hide yes)
			)
		)
		(property "License" "Apache-2.0"
			(at 245.11 101.6 0)
			(effects
				(font
					(size 1.27 1.27)
					(thickness 0.15)
				)
				(justify left bottom)
				(hide yes)
			)
		)
		(pin "1"
		)
		(pin "2"
		)
		(pin "3"
		)
		(pin "4"
		)
		(pin "MP"
		)
		(instances
			(project "jetson-orin-baseboard"
				(path ""
					(reference "J14")
					(unit 1)
				)
			)
		)
	)
	(symbol
		(lib_id "antmicropower:GND")
		(at 246.38 186.69 0)
		(unit 1)
		(exclude_from_sim no)
		(in_bom yes)
		(on_board yes)
		(dnp no)
		(fields_autoplaced yes)
		(property "Reference" "#PWR0241"
			(at 246.38 193.04 0)
			(effects
				(font
					(size 1.27 1.27)
				)
				(justify left bottom)
				(hide yes)
			)
		)
		(property "Value" "GND"
			(at 246.38 190.5 0)
			(effects
				(font
					(size 1.27 1.27)
					(thickness 0.15)
				)
			)
		)
		(property "Footprint" ""
			(at 255.27 194.31 0)
			(effects
				(font
					(size 1.27 1.27)
					(thickness 0.15)
				)
				(justify left bottom)
				(hide yes)
			)
		)
		(property "Datasheet" ""
			(at 255.27 199.39 0)
			(effects
				(font
					(size 1.27 1.27)
					(thickness 0.15)
				)
				(justify left bottom)
				(hide yes)
			)
		)
		(property "Description" ""
			(at 246.38 186.69 0)
			(effects
				(font
					(size 1.27 1.27)
				)
				(hide yes)
			)
		)
		(property "Author" "Antmicro"
			(at 255.27 194.31 0)
			(effects
				(font
					(size 1.27 1.27)
					(thickness 0.15)
				)
				(justify left bottom)
				(hide yes)
			)
		)
		(property "License" "Apache-2.0"
			(at 255.27 196.85 0)
			(effects
				(font
					(size 1.27 1.27)
					(thickness 0.15)
				)
				(justify left bottom)
				(hide yes)
			)
		)
		(pin "1"
		)
		(instances
			(project "jetson-orin-baseboard"
				(path ""
					(reference "#PWR0241")
					(unit 1)
				)
			)
		)
	)
	(symbol
		(lib_id "antmicropower:GND")
		(at 57.15 175.26 0)
		(unit 1)
		(exclude_from_sim no)
		(in_bom yes)
		(on_board yes)
		(dnp no)
		(fields_autoplaced yes)
		(property "Reference" "#PWR0226"
			(at 57.15 181.61 0)
			(effects
				(font
					(size 1.27 1.27)
				)
				(justify left bottom)
				(hide yes)
			)
		)
		(property "Value" "GND"
			(at 57.15 179.07 0)
			(effects
				(font
					(size 1.27 1.27)
					(thickness 0.15)
				)
			)
		)
		(property "Footprint" ""
			(at 66.04 182.88 0)
			(effects
				(font
					(size 1.27 1.27)
					(thickness 0.15)
				)
				(justify left bottom)
				(hide yes)
			)
		)
		(property "Datasheet" ""
			(at 66.04 187.96 0)
			(effects
				(font
					(size 1.27 1.27)
					(thickness 0.15)
				)
				(justify left bottom)
				(hide yes)
			)
		)
		(property "Description" ""
			(at 57.15 175.26 0)
			(effects
				(font
					(size 1.27 1.27)
				)
				(hide yes)
			)
		)
		(property "Author" "Antmicro"
			(at 66.04 182.88 0)
			(effects
				(font
					(size 1.27 1.27)
					(thickness 0.15)
				)
				(justify left bottom)
				(hide yes)
			)
		)
		(property "License" "Apache-2.0"
			(at 66.04 185.42 0)
			(effects
				(font
					(size 1.27 1.27)
					(thickness 0.15)
				)
				(justify left bottom)
				(hide yes)
			)
		)
		(pin "1"
		)
		(instances
			(project "jetson-orin-baseboard"
				(path ""
					(reference "#PWR0226")
					(unit 1)
				)
			)
		)
	)
	(symbol
		(lib_id "antmicroTVSDiodes:TPD1E0B04_XDFN-2")
		(at 388.62 208.28 0)
		(unit 1)
		(exclude_from_sim no)
		(in_bom yes)
		(on_board yes)
		(dnp no)
		(property "Reference" "D47"
			(at 393.065 207.645 0)
			(effects
				(font
					(size 1.27 1.27)
				)
				(justify left bottom)
			)
		)
		(property "Value" "TPD1E0B04_XDFN-2"
			(at 403.86 218.44 0)
			(effects
				(font
					(size 1.27 1.27)
					(thickness 0.15)
				)
				(justify left bottom)
				(hide yes)
			)
		)
		(property "Footprint" "antmicro-footprints:XDFN-2_1x0.60mm"
			(at 403.86 213.36 0)
			(effects
				(font
					(size 1.27 1.27)
					(thickness 0.15)
				)
				(justify left bottom)
				(hide yes)
			)
		)
		(property "Datasheet" "https://www.ti.com/general/docs/suppproductinfo.tsp?distId=26&gotoUrl=https://www.ti.com/lit/gpn/tpd1e0b04"
			(at 403.86 215.9 0)
			(effects
				(font
					(size 1.27 1.27)
					(thickness 0.15)
				)
				(justify left bottom)
				(hide yes)
			)
		)
		(property "Description" ""
			(at 388.62 208.28 0)
			(effects
				(font
					(size 1.27 1.27)
				)
				(hide yes)
			)
		)
		(property "Manufacturer" "Texas Instruments"
			(at 403.86 220.98 0)
			(effects
				(font
					(size 1.27 1.27)
					(thickness 0.15)
				)
				(justify left bottom)
				(hide yes)
			)
		)
		(property "MPN" "TPD1E0B04DPYR"
			(at 373.38 207.645 0)
			(effects
				(font
					(size 1.27 1.27)
					(thickness 0.15)
				)
				(justify left bottom)
			)
		)
		(property "Author" "Antmicro"
			(at 403.86 223.52 0)
			(effects
				(font
					(size 1.27 1.27)
					(thickness 0.15)
				)
				(justify left bottom)
				(hide yes)
			)
		)
		(property "License" "Apache-2.0"
			(at 403.86 226.06 0)
			(effects
				(font
					(size 1.27 1.27)
					(thickness 0.15)
				)
				(justify left bottom)
				(hide yes)
			)
		)
		(pin "1"
		)
		(pin "2"
		)
		(instances
			(project "jetson-orin-baseboard"
				(path ""
					(reference "D47")
					(unit 1)
				)
			)
		)
	)
	(symbol
		(lib_id "antmicroResistorNetworksArrays:R_4x330R_0402_array")
		(at 199.39 144.78 180)
		(unit 1)
		(exclude_from_sim no)
		(in_bom yes)
		(on_board yes)
		(dnp no)
		(property "Reference" "R64"
			(at 194.31 131.445 0)
			(effects
				(font
					(size 1.27 1.27)
				)
			)
		)
		(property "Value" "R_4x330R_0402_array"
			(at 172.72 139.7 0)
			(effects
				(font
					(size 1.27 1.27)
					(thickness 0.15)
				)
				(justify left bottom)
				(hide yes)
			)
		)
		(property "Footprint" "antmicro-footprints:R_Array_4x0402"
			(at 172.72 134.62 0)
			(effects
				(font
					(size 1.27 1.27)
					(thickness 0.15)
				)
				(justify left bottom)
				(hide yes)
			)
		)
		(property "Datasheet" "http://industrial.panasonic.com/cdbs/www-data/pdf/AOC0000/AOC0000C14.pdf"
			(at 172.72 132.08 0)
			(effects
				(font
					(size 1.27 1.27)
					(thickness 0.15)
				)
				(justify left bottom)
				(hide yes)
			)
		)
		(property "Description" ""
			(at 199.39 144.78 0)
			(effects
				(font
					(size 1.27 1.27)
				)
				(hide yes)
			)
		)
		(property "MPN" "EXB-28V331JX"
			(at 172.72 129.54 0)
			(effects
				(font
					(size 1.27 1.27)
					(thickness 0.15)
				)
				(justify left bottom)
				(hide yes)
			)
		)
		(property "Manufacturer" "Panasonic"
			(at 172.72 127 0)
			(effects
				(font
					(size 1.27 1.27)
					(thickness 0.15)
				)
				(justify left bottom)
				(hide yes)
			)
		)
		(property "Author" "Antmicro"
			(at 172.72 124.46 0)
			(effects
				(font
					(size 1.27 1.27)
					(thickness 0.15)
				)
				(justify left bottom)
				(hide yes)
			)
		)
		(property "License" "Apache-2.0"
			(at 172.72 121.92 0)
			(effects
				(font
					(size 1.27 1.27)
					(thickness 0.15)
				)
				(justify left bottom)
				(hide yes)
			)
		)
		(property "Val" "R_4x330R_0402"
			(at 194.31 133.985 0)
			(effects
				(font
					(size 1.27 1.27)
				)
			)
		)
		(pin "1"
		)
		(pin "2"
		)
		(pin "3"
		)
		(pin "4"
		)
		(pin "5"
		)
		(pin "6"
		)
		(pin "7"
		)
		(pin "8"
		)
		(instances
			(project "jetson-orin-baseboard"
				(path ""
					(reference "R64")
					(unit 1)
				)
			)
		)
	)
	(symbol
		(lib_id "antmicroTVSDiodes:TPD1E0B04_XDFN-2")
		(at 388.62 203.2 0)
		(unit 1)
		(exclude_from_sim no)
		(in_bom yes)
		(on_board yes)
		(dnp no)
		(property "Reference" "D46"
			(at 393.065 202.565 0)
			(effects
				(font
					(size 1.27 1.27)
				)
				(justify left bottom)
			)
		)
		(property "Value" "TPD1E0B04_XDFN-2"
			(at 403.86 213.36 0)
			(effects
				(font
					(size 1.27 1.27)
					(thickness 0.15)
				)
				(justify left bottom)
				(hide yes)
			)
		)
		(property "Footprint" "antmicro-footprints:XDFN-2_1x0.60mm"
			(at 403.86 208.28 0)
			(effects
				(font
					(size 1.27 1.27)
					(thickness 0.15)
				)
				(justify left bottom)
				(hide yes)
			)
		)
		(property "Datasheet" "https://www.ti.com/general/docs/suppproductinfo.tsp?distId=26&gotoUrl=https://www.ti.com/lit/gpn/tpd1e0b04"
			(at 403.86 210.82 0)
			(effects
				(font
					(size 1.27 1.27)
					(thickness 0.15)
				)
				(justify left bottom)
				(hide yes)
			)
		)
		(property "Description" ""
			(at 388.62 203.2 0)
			(effects
				(font
					(size 1.27 1.27)
				)
				(hide yes)
			)
		)
		(property "Manufacturer" "Texas Instruments"
			(at 403.86 215.9 0)
			(effects
				(font
					(size 1.27 1.27)
					(thickness 0.15)
				)
				(justify left bottom)
				(hide yes)
			)
		)
		(property "MPN" "TPD1E0B04DPYR"
			(at 373.38 202.565 0)
			(effects
				(font
					(size 1.27 1.27)
					(thickness 0.15)
				)
				(justify left bottom)
			)
		)
		(property "Author" "Antmicro"
			(at 403.86 218.44 0)
			(effects
				(font
					(size 1.27 1.27)
					(thickness 0.15)
				)
				(justify left bottom)
				(hide yes)
			)
		)
		(property "License" "Apache-2.0"
			(at 403.86 220.98 0)
			(effects
				(font
					(size 1.27 1.27)
					(thickness 0.15)
				)
				(justify left bottom)
				(hide yes)
			)
		)
		(pin "1"
		)
		(pin "2"
		)
		(instances
			(project "jetson-orin-baseboard"
				(path ""
					(reference "D46")
					(unit 1)
				)
			)
		)
	)
	(symbol
		(lib_id "antmicroB2BConnectors:Socket_Samtec_ERF8_2x40_ERF8-040-05.0-L-DV-K-TR")
		(at 320.04 35.56 0)
		(unit 1)
		(exclude_from_sim no)
		(in_bom yes)
		(on_board yes)
		(dnp no)
		(fields_autoplaced yes)
		(property "Reference" "J11"
			(at 325.755 27.94 0)
			(effects
				(font
					(size 1.27 1.27)
				)
			)
		)
		(property "Value" "Socket_Samtec_ERF8_2x40_ERF8-040-05.0-L-DV-K-TR"
			(at 350.52 40.64 0)
			(effects
				(font
					(size 1.27 1.27)
					(thickness 0.15)
				)
				(justify left bottom)
				(hide yes)
			)
		)
		(property "Footprint" "antmicro-footprints:Conn_Socket_Samtec_ERF8_2x40_ERF8-040-05.0-L-DV-K-TR"
			(at 350.52 43.18 0)
			(effects
				(font
					(size 1.27 1.27)
					(thickness 0.15)
				)
				(justify left bottom)
				(hide yes)
			)
		)
		(property "Datasheet" "https://suddendocs.samtec.com/catalog_english/erf8.pdf"
			(at 350.52 45.72 0)
			(effects
				(font
					(size 1.27 1.27)
					(thickness 0.15)
				)
				(justify left bottom)
				(hide yes)
			)
		)
		(property "Description" ""
			(at 320.04 35.56 0)
			(effects
				(font
					(size 1.27 1.27)
				)
				(hide yes)
			)
		)
		(property "MPN" "ERF8-040-05.0-L-DV-K-TR"
			(at 325.755 30.48 0)
			(effects
				(font
					(size 1.27 1.27)
					(thickness 0.15)
				)
			)
		)
		(property "Manufacturer" "Samtec"
			(at 350.52 48.26 0)
			(effects
				(font
					(size 1.27 1.27)
					(thickness 0.15)
				)
				(justify left bottom)
				(hide yes)
			)
		)
		(property "Author" "Antmicro"
			(at 350.52 53.34 0)
			(effects
				(font
					(size 1.27 1.27)
					(thickness 0.15)
				)
				(justify left bottom)
				(hide yes)
			)
		)
		(property "License" "Apache-2.0"
			(at 350.52 55.88 0)
			(effects
				(font
					(size 1.27 1.27)
					(thickness 0.15)
				)
				(justify left bottom)
				(hide yes)
			)
		)
		(property "Pitch" "0.8 mm"
			(at 350.52 50.8 0)
			(effects
				(font
					(size 1.27 1.27)
				)
				(justify left bottom)
				(hide yes)
			)
		)
		(pin "1"
		)
		(pin "10"
		)
		(pin "11"
		)
		(pin "12"
		)
		(pin "13"
		)
		(pin "14"
		)
		(pin "15"
		)
		(pin "16"
		)
		(pin "17"
		)
		(pin "18"
		)
		(pin "19"
		)
		(pin "2"
		)
		(pin "20"
		)
		(pin "21"
		)
		(pin "22"
		)
		(pin "23"
		)
		(pin "24"
		)
		(pin "25"
		)
		(pin "26"
		)
		(pin "27"
		)
		(pin "28"
		)
		(pin "29"
		)
		(pin "3"
		)
		(pin "30"
		)
		(pin "31"
		)
		(pin "32"
		)
		(pin "33"
		)
		(pin "34"
		)
		(pin "35"
		)
		(pin "36"
		)
		(pin "37"
		)
		(pin "38"
		)
		(pin "39"
		)
		(pin "4"
		)
		(pin "40"
		)
		(pin "41"
		)
		(pin "42"
		)
		(pin "43"
		)
		(pin "44"
		)
		(pin "45"
		)
		(pin "46"
		)
		(pin "47"
		)
		(pin "48"
		)
		(pin "49"
		)
		(pin "5"
		)
		(pin "50"
		)
		(pin "51"
		)
		(pin "52"
		)
		(pin "53"
		)
		(pin "54"
		)
		(pin "55"
		)
		(pin "56"
		)
		(pin "57"
		)
		(pin "58"
		)
		(pin "59"
		)
		(pin "6"
		)
		(pin "60"
		)
		(pin "61"
		)
		(pin "62"
		)
		(pin "63"
		)
		(pin "64"
		)
		(pin "65"
		)
		(pin "66"
		)
		(pin "67"
		)
		(pin "68"
		)
		(pin "69"
		)
		(pin "7"
		)
		(pin "70"
		)
		(pin "71"
		)
		(pin "72"
		)
		(pin "73"
		)
		(pin "74"
		)
		(pin "75"
		)
		(pin "76"
		)
		(pin "77"
		)
		(pin "78"
		)
		(pin "79"
		)
		(pin "8"
		)
		(pin "80"
		)
		(pin "9"
		)
		(instances
			(project "jetson-orin-baseboard"
				(path ""
					(reference "J11")
					(unit 1)
				)
			)
		)
	)
	(symbol
		(lib_id "antmicropower:GND")
		(at 267.97 275.59 0)
		(unit 1)
		(exclude_from_sim no)
		(in_bom yes)
		(on_board yes)
		(dnp no)
		(fields_autoplaced yes)
		(property "Reference" "#PWR0315"
			(at 267.97 281.94 0)
			(effects
				(font
					(size 1.27 1.27)
				)
				(justify left bottom)
				(hide yes)
			)
		)
		(property "Value" "GND"
			(at 267.97 279.4 0)
			(effects
				(font
					(size 1.27 1.27)
					(thickness 0.15)
				)
			)
		)
		(property "Footprint" ""
			(at 276.86 283.21 0)
			(effects
				(font
					(size 1.27 1.27)
					(thickness 0.15)
				)
				(justify left bottom)
				(hide yes)
			)
		)
		(property "Datasheet" ""
			(at 276.86 288.29 0)
			(effects
				(font
					(size 1.27 1.27)
					(thickness 0.15)
				)
				(justify left bottom)
				(hide yes)
			)
		)
		(property "Description" ""
			(at 267.97 275.59 0)
			(effects
				(font
					(size 1.27 1.27)
				)
				(hide yes)
			)
		)
		(property "Author" "Antmicro"
			(at 276.86 283.21 0)
			(effects
				(font
					(size 1.27 1.27)
					(thickness 0.15)
				)
				(justify left bottom)
				(hide yes)
			)
		)
		(property "License" "Apache-2.0"
			(at 276.86 285.75 0)
			(effects
				(font
					(size 1.27 1.27)
					(thickness 0.15)
				)
				(justify left bottom)
				(hide yes)
			)
		)
		(pin "1"
		)
		(instances
			(project "jetson-orin-baseboard"
				(path ""
					(reference "#PWR0315")
					(unit 1)
				)
			)
		)
	)
	(symbol
		(lib_id "antmicroCapacitors0402:C_100n_0402")
		(at 281.94 60.96 180)
		(unit 1)
		(exclude_from_sim no)
		(in_bom yes)
		(on_board yes)
		(dnp no)
		(property "Reference" "C113"
			(at 280.67 60.325 0)
			(effects
				(font
					(size 1.27 1.27)
				)
				(justify right top)
			)
		)
		(property "Value" "C_100n_0402"
			(at 261.62 50.8 0)
			(effects
				(font
					(size 1.27 1.27)
					(thickness 0.15)
				)
				(justify left bottom)
				(hide yes)
			)
		)
		(property "Footprint" "antmicro-footprints:C_0402_1005Metric"
			(at 261.62 48.26 0)
			(effects
				(font
					(size 1.27 1.27)
					(thickness 0.15)
				)
				(justify left bottom)
				(hide yes)
			)
		)
		(property "Datasheet" "https://www.murata.com/products/productdetail?partno=GRM155R61H104KE14%23"
			(at 261.62 45.72 0)
			(effects
				(font
					(size 1.27 1.27)
					(thickness 0.15)
				)
				(justify left bottom)
				(hide yes)
			)
		)
		(property "Description" ""
			(at 281.94 60.96 0)
			(effects
				(font
					(size 1.27 1.27)
				)
				(hide yes)
			)
		)
		(property "Manufacturer" "Murata"
			(at 261.62 40.64 0)
			(effects
				(font
					(size 1.27 1.27)
					(thickness 0.15)
				)
				(justify left bottom)
				(hide yes)
			)
		)
		(property "MPN" "GRM155R61H104KE14D"
			(at 261.62 43.18 0)
			(effects
				(font
					(size 1.27 1.27)
					(thickness 0.15)
				)
				(justify left bottom)
				(hide yes)
			)
		)
		(property "Val" "100n"
			(at 278.13 61.595 0)
			(effects
				(font
					(size 1.27 1.27)
					(thickness 0.15)
				)
				(justify left bottom)
			)
		)
		(property "License" "Apache-2.0"
			(at 261.62 38.1 0)
			(effects
				(font
					(size 1.27 1.27)
					(thickness 0.15)
				)
				(justify left bottom)
				(hide yes)
			)
		)
		(property "Author" "Antmicro"
			(at 261.62 35.56 0)
			(effects
				(font
					(size 1.27 1.27)
					(thickness 0.15)
				)
				(justify left bottom)
				(hide yes)
			)
		)
		(property "Voltage" "50V"
			(at 261.62 33.02 0)
			(effects
				(font
					(size 1.27 1.27)
				)
				(justify left bottom)
				(hide yes)
			)
		)
		(property "Dielectric" "X5R"
			(at 261.62 30.48 0)
			(effects
				(font
					(size 1.27 1.27)
				)
				(justify left bottom)
				(hide yes)
			)
		)
		(pin "1"
		)
		(pin "2"
		)
		(instances
			(project "jetson-orin-baseboard"
				(path ""
					(reference "C113")
					(unit 1)
				)
			)
		)
	)
	(symbol
		(lib_id "antmicroTVSDiodes:TPD1E0B04_XDFN-2")
		(at 388.62 177.8 0)
		(unit 1)
		(exclude_from_sim no)
		(in_bom yes)
		(on_board yes)
		(dnp no)
		(property "Reference" "D41"
			(at 393.065 177.165 0)
			(effects
				(font
					(size 1.27 1.27)
				)
				(justify left bottom)
			)
		)
		(property "Value" "TPD1E0B04_XDFN-2"
			(at 403.86 187.96 0)
			(effects
				(font
					(size 1.27 1.27)
					(thickness 0.15)
				)
				(justify left bottom)
				(hide yes)
			)
		)
		(property "Footprint" "antmicro-footprints:XDFN-2_1x0.60mm"
			(at 403.86 182.88 0)
			(effects
				(font
					(size 1.27 1.27)
					(thickness 0.15)
				)
				(justify left bottom)
				(hide yes)
			)
		)
		(property "Datasheet" "https://www.ti.com/general/docs/suppproductinfo.tsp?distId=26&gotoUrl=https://www.ti.com/lit/gpn/tpd1e0b04"
			(at 403.86 185.42 0)
			(effects
				(font
					(size 1.27 1.27)
					(thickness 0.15)
				)
				(justify left bottom)
				(hide yes)
			)
		)
		(property "Description" ""
			(at 388.62 177.8 0)
			(effects
				(font
					(size 1.27 1.27)
				)
				(hide yes)
			)
		)
		(property "Manufacturer" "Texas Instruments"
			(at 403.86 190.5 0)
			(effects
				(font
					(size 1.27 1.27)
					(thickness 0.15)
				)
				(justify left bottom)
				(hide yes)
			)
		)
		(property "MPN" "TPD1E0B04DPYR"
			(at 373.38 177.165 0)
			(effects
				(font
					(size 1.27 1.27)
					(thickness 0.15)
				)
				(justify left bottom)
			)
		)
		(property "Author" "Antmicro"
			(at 403.86 193.04 0)
			(effects
				(font
					(size 1.27 1.27)
					(thickness 0.15)
				)
				(justify left bottom)
				(hide yes)
			)
		)
		(property "License" "Apache-2.0"
			(at 403.86 195.58 0)
			(effects
				(font
					(size 1.27 1.27)
					(thickness 0.15)
				)
				(justify left bottom)
				(hide yes)
			)
		)
		(pin "1"
		)
		(pin "2"
		)
		(instances
			(project "jetson-orin-baseboard"
				(path ""
					(reference "D41")
					(unit 1)
				)
			)
		)
	)
	(symbol
		(lib_id "antmicroTVSDiodes:TPD1E0B04_XDFN-2")
		(at 388.62 228.6 0)
		(unit 1)
		(exclude_from_sim no)
		(in_bom yes)
		(on_board yes)
		(dnp no)
		(property "Reference" "D16"
			(at 393.065 227.965 0)
			(effects
				(font
					(size 1.27 1.27)
				)
				(justify left bottom)
			)
		)
		(property "Value" "TPD1E0B04_XDFN-2"
			(at 403.86 238.76 0)
			(effects
				(font
					(size 1.27 1.27)
					(thickness 0.15)
				)
				(justify left bottom)
				(hide yes)
			)
		)
		(property "Footprint" "antmicro-footprints:XDFN-2_1x0.60mm"
			(at 403.86 233.68 0)
			(effects
				(font
					(size 1.27 1.27)
					(thickness 0.15)
				)
				(justify left bottom)
				(hide yes)
			)
		)
		(property "Datasheet" "https://www.ti.com/general/docs/suppproductinfo.tsp?distId=26&gotoUrl=https://www.ti.com/lit/gpn/tpd1e0b04"
			(at 403.86 236.22 0)
			(effects
				(font
					(size 1.27 1.27)
					(thickness 0.15)
				)
				(justify left bottom)
				(hide yes)
			)
		)
		(property "Description" ""
			(at 388.62 228.6 0)
			(effects
				(font
					(size 1.27 1.27)
				)
				(hide yes)
			)
		)
		(property "Manufacturer" "Texas Instruments"
			(at 403.86 241.3 0)
			(effects
				(font
					(size 1.27 1.27)
					(thickness 0.15)
				)
				(justify left bottom)
				(hide yes)
			)
		)
		(property "MPN" "TPD1E0B04DPYR"
			(at 373.38 227.965 0)
			(effects
				(font
					(size 1.27 1.27)
					(thickness 0.15)
				)
				(justify left bottom)
			)
		)
		(property "Author" "Antmicro"
			(at 403.86 243.84 0)
			(effects
				(font
					(size 1.27 1.27)
					(thickness 0.15)
				)
				(justify left bottom)
				(hide yes)
			)
		)
		(property "License" "Apache-2.0"
			(at 403.86 246.38 0)
			(effects
				(font
					(size 1.27 1.27)
					(thickness 0.15)
				)
				(justify left bottom)
				(hide yes)
			)
		)
		(pin "1"
		)
		(pin "2"
		)
		(instances
			(project "jetson-orin-baseboard"
				(path ""
					(reference "D16")
					(unit 1)
				)
			)
		)
	)
	(symbol
		(lib_id "antmicroPushbuttonSwitches:SW_KMR211NGLFS_SMD")
		(at 267.97 262.89 270)
		(unit 1)
		(exclude_from_sim no)
		(in_bom yes)
		(on_board yes)
		(dnp no)
		(property "Reference" "S3"
			(at 271.78 266.7 90)
			(effects
				(font
					(size 1.27 1.27)
				)
				(justify left)
			)
		)
		(property "Value" "SW_KMR211NGLFS_SMD"
			(at 260.35 288.29 0)
			(effects
				(font
					(size 1.27 1.27)
					(thickness 0.15)
				)
				(justify left bottom)
				(hide yes)
			)
		)
		(property "Footprint" "antmicro-footprints:SW_KMR211NGLFS_SMD"
			(at 257.81 288.29 0)
			(effects
				(font
					(size 1.27 1.27)
					(thickness 0.15)
				)
				(justify left bottom)
				(hide yes)
			)
		)
		(property "Datasheet" "http://www.farnell.com/datasheets/2631211.pdf"
			(at 255.27 288.29 0)
			(effects
				(font
					(size 1.27 1.27)
					(thickness 0.15)
				)
				(justify left bottom)
				(hide yes)
			)
		)
		(property "Description" ""
			(at 267.97 262.89 0)
			(effects
				(font
					(size 1.27 1.27)
				)
				(hide yes)
			)
		)
		(property "MPN" "KMR211NGLFS"
			(at 271.78 269.24 90)
			(effects
				(font
					(size 1.27 1.27)
					(thickness 0.15)
				)
				(justify left)
			)
		)
		(property "Manufacturer" "C&K"
			(at 252.73 288.29 0)
			(effects
				(font
					(size 1.27 1.27)
					(thickness 0.15)
				)
				(justify left bottom)
				(hide yes)
			)
		)
		(property "Author" "Antmicro"
			(at 250.19 288.29 0)
			(effects
				(font
					(size 1.27 1.27)
					(thickness 0.15)
				)
				(justify left bottom)
				(hide yes)
			)
		)
		(property "License" "Apache-2.0"
			(at 247.65 288.29 0)
			(effects
				(font
					(size 1.27 1.27)
					(thickness 0.15)
				)
				(justify left bottom)
				(hide yes)
			)
		)
		(pin "1"
		)
		(pin "2"
		)
		(pin "3"
		)
		(pin "4"
		)
		(instances
			(project "jetson-orin-baseboard"
				(path ""
					(reference "S3")
					(unit 1)
				)
			)
		)
	)
	(symbol
		(lib_id "antmicropower:GND")
		(at 90.17 85.09 0)
		(unit 1)
		(exclude_from_sim no)
		(in_bom yes)
		(on_board yes)
		(dnp no)
		(fields_autoplaced yes)
		(property "Reference" "#PWR0203"
			(at 90.17 91.44 0)
			(effects
				(font
					(size 1.27 1.27)
				)
				(justify left bottom)
				(hide yes)
			)
		)
		(property "Value" "GND"
			(at 90.17 88.9 0)
			(effects
				(font
					(size 1.27 1.27)
					(thickness 0.15)
				)
			)
		)
		(property "Footprint" ""
			(at 99.06 92.71 0)
			(effects
				(font
					(size 1.27 1.27)
					(thickness 0.15)
				)
				(justify left bottom)
				(hide yes)
			)
		)
		(property "Datasheet" ""
			(at 99.06 97.79 0)
			(effects
				(font
					(size 1.27 1.27)
					(thickness 0.15)
				)
				(justify left bottom)
				(hide yes)
			)
		)
		(property "Description" ""
			(at 90.17 85.09 0)
			(effects
				(font
					(size 1.27 1.27)
				)
				(hide yes)
			)
		)
		(property "Author" "Antmicro"
			(at 99.06 92.71 0)
			(effects
				(font
					(size 1.27 1.27)
					(thickness 0.15)
				)
				(justify left bottom)
				(hide yes)
			)
		)
		(property "License" "Apache-2.0"
			(at 99.06 95.25 0)
			(effects
				(font
					(size 1.27 1.27)
					(thickness 0.15)
				)
				(justify left bottom)
				(hide yes)
			)
		)
		(pin "1"
		)
		(instances
			(project "jetson-orin-baseboard"
				(path ""
					(reference "#PWR0203")
					(unit 1)
				)
			)
		)
	)
	(symbol
		(lib_id "antmicroResistorNetworksArrays:R_4x0R_0201_array")
		(at 87.63 232.41 0)
		(unit 1)
		(exclude_from_sim no)
		(in_bom yes)
		(on_board yes)
		(dnp no)
		(property "Reference" "R204"
			(at 92.71 226.695 0)
			(effects
				(font
					(size 1.27 1.27)
				)
			)
		)
		(property "Value" "R_4x0R_0201_array"
			(at 114.3 240.03 0)
			(effects
				(font
					(size 1.27 1.27)
					(thickness 0.15)
				)
				(justify left bottom)
				(hide yes)
			)
		)
		(property "Footprint" "antmicro-footprints:R_Array_4x0201_Panasonic_EXB18V"
			(at 114.3 245.11 0)
			(effects
				(font
					(size 1.27 1.27)
					(thickness 0.15)
				)
				(justify left bottom)
				(hide yes)
			)
		)
		(property "Datasheet" "http://industrial.panasonic.com/cdbs/www-data/pdf/AOC0000/AOC0000C14.pdf"
			(at 114.3 247.65 0)
			(effects
				(font
					(size 1.27 1.27)
					(thickness 0.15)
				)
				(justify left bottom)
				(hide yes)
			)
		)
		(property "Description" ""
			(at 87.63 232.41 0)
			(effects
				(font
					(size 1.27 1.27)
				)
				(hide yes)
			)
		)
		(property "MPN" "EXB-18VR000X"
			(at 114.3 250.19 0)
			(effects
				(font
					(size 1.27 1.27)
					(thickness 0.15)
				)
				(justify left bottom)
				(hide yes)
			)
		)
		(property "Manufacturer" "Panasonic"
			(at 114.3 252.73 0)
			(effects
				(font
					(size 1.27 1.27)
					(thickness 0.15)
				)
				(justify left bottom)
				(hide yes)
			)
		)
		(property "Val" "4x0R_0201"
			(at 92.71 229.235 0)
			(effects
				(font
					(size 1.27 1.27)
					(thickness 0.15)
				)
			)
		)
		(property "Author" "Antmicro"
			(at 114.3 255.27 0)
			(effects
				(font
					(size 1.27 1.27)
					(thickness 0.15)
				)
				(justify left bottom)
				(hide yes)
			)
		)
		(property "License" "Apache-2.0"
			(at 114.3 257.81 0)
			(effects
				(font
					(size 1.27 1.27)
					(thickness 0.15)
				)
				(justify left bottom)
				(hide yes)
			)
		)
		(pin "1"
		)
		(pin "2"
		)
		(pin "3"
		)
		(pin "4"
		)
		(pin "5"
		)
		(pin "6"
		)
		(pin "7"
		)
		(pin "8"
		)
		(instances
			(project "jetson-orin-baseboard"
				(path ""
					(reference "R204")
					(unit 1)
				)
			)
		)
	)
	(symbol
		(lib_id "antmicroTVSDiodes:TPD1E0B04_XDFN-2")
		(at 388.62 213.36 0)
		(unit 1)
		(exclude_from_sim no)
		(in_bom yes)
		(on_board yes)
		(dnp no)
		(property "Reference" "D48"
			(at 393.065 212.725 0)
			(effects
				(font
					(size 1.27 1.27)
				)
				(justify left bottom)
			)
		)
		(property "Value" "TPD1E0B04_XDFN-2"
			(at 403.86 223.52 0)
			(effects
				(font
					(size 1.27 1.27)
					(thickness 0.15)
				)
				(justify left bottom)
				(hide yes)
			)
		)
		(property "Footprint" "antmicro-footprints:XDFN-2_1x0.60mm"
			(at 403.86 218.44 0)
			(effects
				(font
					(size 1.27 1.27)
					(thickness 0.15)
				)
				(justify left bottom)
				(hide yes)
			)
		)
		(property "Datasheet" "https://www.ti.com/general/docs/suppproductinfo.tsp?distId=26&gotoUrl=https://www.ti.com/lit/gpn/tpd1e0b04"
			(at 403.86 220.98 0)
			(effects
				(font
					(size 1.27 1.27)
					(thickness 0.15)
				)
				(justify left bottom)
				(hide yes)
			)
		)
		(property "Description" ""
			(at 388.62 213.36 0)
			(effects
				(font
					(size 1.27 1.27)
				)
				(hide yes)
			)
		)
		(property "Manufacturer" "Texas Instruments"
			(at 403.86 226.06 0)
			(effects
				(font
					(size 1.27 1.27)
					(thickness 0.15)
				)
				(justify left bottom)
				(hide yes)
			)
		)
		(property "MPN" "TPD1E0B04DPYR"
			(at 373.38 212.725 0)
			(effects
				(font
					(size 1.27 1.27)
					(thickness 0.15)
				)
				(justify left bottom)
			)
		)
		(property "Author" "Antmicro"
			(at 403.86 228.6 0)
			(effects
				(font
					(size 1.27 1.27)
					(thickness 0.15)
				)
				(justify left bottom)
				(hide yes)
			)
		)
		(property "License" "Apache-2.0"
			(at 403.86 231.14 0)
			(effects
				(font
					(size 1.27 1.27)
					(thickness 0.15)
				)
				(justify left bottom)
				(hide yes)
			)
		)
		(pin "1"
		)
		(pin "2"
		)
		(instances
			(project "jetson-orin-baseboard"
				(path ""
					(reference "D48")
					(unit 1)
				)
			)
		)
	)
)
